G04 ================== begin FILE IDENTIFICATION RECORD ==================*
G04 Layout Name:  t6mg_pdb_a_v02_0109_1330.brd*
G04 Film Name:    gnd*
G04 File Format:  Gerber RS274X*
G04 File Origin:  Cadence Allegro 16.3-S038*
G04 Origin Date:  Mon Jan 13 14:11:52 2014*
G04 *
G04 Layer:  DRAWING FORMAT/TITLE_BLOCK*
G04 Layer:  VIA CLASS/GND*
G04 Layer:  PIN/GND*
G04 Layer:  MANUFACTURING/PHOTOPLOT_OUTLINE*
G04 Layer:  ETCH/GND*
G04 Layer:  DRAWING FORMAT/TITLE_DATA_GND*
G04 *
G04 Offset:    (0.00 0.00)*
G04 Mirror:    No*
G04 Mode:      Negative*
G04 Rotation:  0*
G04 FullContactRelief:  No*
G04 UndefLineWidth:     6.00*
G04 ================== end FILE IDENTIFICATION RECORD ====================*
%FSLAX25Y25*MOIN*%
%IR0*IPPOS*OFA0.00000B0.00000*MIA0B0*SFA1.00000B1.00000*%
%ADD24C,.03*%
%ADD34C,.05*%
%AMMACRO27*
4,1,36,0.0,.01,
-.001736,.009848,
-.00342,.009397,
-.005,.00866,
-.006428,.00766,
-.00766,.006428,
-.00866,.005,
-.009397,.00342,
-.009848,.001736,
-.01,0.0,
-.009848,-.001736,
-.009397,-.00342,
-.00866,-.005,
-.00766,-.006428,
-.006428,-.00766,
-.005,-.00866,
-.00342,-.009397,
-.001736,-.009848,
0.0,-.01,
.001736,-.009848,
.00342,-.009397,
.005,-.00866,
.006428,-.00766,
.00766,-.006428,
.00866,-.005,
.009397,-.00342,
.009848,-.001736,
.01,0.0,
.009848,.001736,
.009397,.00342,
.00866,.005,
.00766,.006428,
.006428,.00766,
.005,.00866,
.00342,.009397,
.001736,.009848,
0.0,.01,
0.0*
%
%ADD27MACRO27*%
%ADD13C,.063*%
%ADD29C,.064*%
%ADD22C,.082*%
%ADD14C,.056*%
%ADD17C,.048*%
%AMMACRO16*
4,1,36,0.0,.004,
.000695,.003939,
.001368,.003759,
.002,.003464,
.002571,.003064,
.003064,.002571,
.003464,.002,
.003759,.001368,
.003939,.000695,
.004,0.0,
.003939,-.000695,
.003759,-.001368,
.003464,-.002,
.003064,-.002571,
.002571,-.003064,
.002,-.003464,
.001368,-.003759,
.000695,-.003939,
0.0,-.004,
-.000695,-.003939,
-.001368,-.003759,
-.002,-.003464,
-.002571,-.003064,
-.003064,-.002571,
-.003464,-.002,
-.003759,-.001368,
-.003939,-.000695,
-.004,0.0,
-.003939,.000695,
-.003759,.001368,
-.003464,.002,
-.003064,.002571,
-.002571,.003064,
-.002,.003464,
-.001368,.003759,
-.000695,.003939,
0.0,.004,
180.*
%
%ADD16MACRO16*%
%ADD25C,.059*%
%ADD20C,.077*%
%AMMACRO12*
4,1,16,.02548,.01487,
.027675,.01022,
.029029,.005259,
.029501,.000138,
.029077,-.004987,
.027769,-.009961,
.025618,-.014631,
.02548,-.01487,
.03056,-.01996,
.033562,-.01435,
.035544,-.008304,
.036446,-.002006,
.03624,.004353,
.034934,.01058,
.032566,.016486,
.03056,.01996,
.02548,.01487,
90.*
4,1,16,.01487,-.02548,
.01022,-.027675,
.005259,-.029029,
.000138,-.029501,
-.004987,-.029077,
-.009961,-.027769,
-.014631,-.025618,
-.01487,-.02548,
-.01996,-.03056,
-.01435,-.033562,
-.008304,-.035544,
-.002006,-.036446,
.004353,-.03624,
.01058,-.034934,
.016486,-.032566,
.01996,-.03056,
.01487,-.02548,
90.*
4,1,16,-.02548,-.01487,
-.027675,-.01022,
-.029029,-.005259,
-.029501,-.000138,
-.029077,.004987,
-.027769,.009961,
-.025618,.014631,
-.02548,.01487,
-.03056,.01996,
-.033562,.01435,
-.035544,.008304,
-.036446,.002006,
-.03624,-.004353,
-.034934,-.01058,
-.032566,-.016486,
-.03056,-.01996,
-.02548,-.01487,
90.*
4,1,16,-.01487,.02548,
-.01022,.027675,
-.005259,.029029,
-.000138,.029501,
.004987,.029077,
.009961,.027769,
.014631,.025618,
.01487,.02548,
.01996,.03056,
.01435,.033562,
.008304,.035544,
.002006,.036446,
-.004353,.03624,
-.01058,.034934,
-.016486,.032566,
-.01996,.03056,
-.01487,.02548,
90.*
%
%ADD12MACRO12*%
%ADD36O,.235X.274*%
%ADD18C,.125*%
%ADD10C,.162*%
%ADD35C,.235*%
%ADD37C,.345*%
%ADD31C,.129*%
%ADD15C,.156*%
%AMMACRO19*
4,1,36,0.0,.013,
-.002257,.012803,
-.004446,.012216,
-.0065,.011258,
-.008356,.009959,
-.009959,.008356,
-.011258,.0065,
-.012216,.004446,
-.012803,.002257,
-.013,0.0,
-.012803,-.002257,
-.012216,-.004446,
-.011258,-.0065,
-.009959,-.008356,
-.008356,-.009959,
-.0065,-.011258,
-.004446,-.012216,
-.002257,-.012803,
0.0,-.013,
.002257,-.012803,
.004446,-.012216,
.0065,-.011258,
.008356,-.009959,
.009959,-.008356,
.011258,-.0065,
.012216,-.004446,
.012803,-.002257,
.013,0.0,
.012803,.002257,
.012216,.004446,
.011258,.0065,
.009959,.008356,
.008356,.009959,
.0065,.011258,
.004446,.012216,
.002257,.012803,
0.0,.013,
270.*
%
%ADD19MACRO19*%
%AMMACRO32*
4,1,36,0.0,.014,
.002431,.013787,
.004788,.013156,
.007,.012124,
.008999,.010725,
.010725,.008999,
.012124,.007,
.013156,.004788,
.013787,.002431,
.014,0.0,
.013787,-.002431,
.013156,-.004788,
.012124,-.007,
.010725,-.008999,
.008999,-.010725,
.007,-.012124,
.004788,-.013156,
.002431,-.013787,
0.0,-.014,
-.002431,-.013787,
-.004788,-.013156,
-.007,-.012124,
-.008999,-.010725,
-.010725,-.008999,
-.012124,-.007,
-.013156,-.004788,
-.013787,-.002431,
-.014,0.0,
-.013787,.002431,
-.013156,.004788,
-.012124,.007,
-.010725,.008999,
-.008999,.010725,
-.007,.012124,
-.004788,.013156,
-.002431,.013787,
0.0,.014,
180.*
%
%ADD32MACRO32*%
%ADD28C,.188*%
%AMMACRO11*
4,1,36,0.0,.004,
.000695,.003939,
.001368,.003759,
.002,.003464,
.002571,.003064,
.003064,.002571,
.003464,.002,
.003759,.001368,
.003939,.000695,
.004,0.0,
.003939,-.000695,
.003759,-.001368,
.003464,-.002,
.003064,-.002571,
.002571,-.003064,
.002,-.003464,
.001368,-.003759,
.000695,-.003939,
0.0,-.004,
-.000695,-.003939,
-.001368,-.003759,
-.002,-.003464,
-.002571,-.003064,
-.003064,-.002571,
-.003464,-.002,
-.003759,-.001368,
-.003939,-.000695,
-.004,0.0,
-.003939,.000695,
-.003759,.001368,
-.003464,.002,
-.003064,.002571,
-.002571,.003064,
-.002,.003464,
-.001368,.003759,
-.000695,.003939,
0.0,.004,
0.0*
%
%ADD11MACRO11*%
%AMMACRO30*
4,1,16,.02584,.01524,
.028094,.010521,
.029494,.005483,
.029998,.000278,
.029591,-.004935,
.028284,-.009999,
.026118,-.014758,
.02584,-.01524,
.03092,-.02032,
.033979,-.014642,
.036005,-.008519,
.036938,-.002138,
.036748,.004309,
.035441,.010625,
.033058,.016618,
.03092,.02032,
.02584,.01524,
270.*
4,1,16,.01524,-.02584,
.010521,-.028094,
.005483,-.029494,
.000278,-.029998,
-.004935,-.029591,
-.009999,-.028284,
-.014758,-.026118,
-.01524,-.02584,
-.02032,-.03092,
-.014642,-.033979,
-.008519,-.036005,
-.002138,-.036938,
.004309,-.036748,
.010625,-.035441,
.016618,-.033058,
.02032,-.03092,
.01524,-.02584,
270.*
4,1,16,-.02584,-.01524,
-.028094,-.010521,
-.029494,-.005483,
-.029998,-.000278,
-.029591,.004935,
-.028284,.009999,
-.026118,.014758,
-.02584,.01524,
-.03092,.02032,
-.033979,.014642,
-.036005,.008519,
-.036938,.002138,
-.036748,-.004309,
-.035441,-.010625,
-.033058,-.016618,
-.03092,-.02032,
-.02584,-.01524,
270.*
4,1,16,-.01524,.02584,
-.010521,.028094,
-.005483,.029494,
-.000278,.029998,
.004935,.029591,
.009999,.028284,
.014758,.026118,
.01524,.02584,
.02032,.03092,
.014642,.033979,
.008519,.036005,
.002138,.036938,
-.004309,.036748,
-.010625,.035441,
-.016618,.033058,
-.02032,.03092,
-.01524,.02584,
270.*
%
%ADD30MACRO30*%
%AMMACRO33*
4,1,15,.02291,.0123,
.024698,.008135,
.025735,.003723,
.025991,-.000803,
.025456,-.005304,
.024149,-.009644,
.02291,-.0123,
.02803,-.01742,
.030629,-.012288,
.032298,-.006783,
.032985,-.001071,
.03267,.004673,
.031362,.010275,
.029101,.015565,
.02803,.01742,
.02291,.0123,
180.*
4,1,15,.0123,-.02291,
.008135,-.024698,
.003723,-.025735,
-.000803,-.025991,
-.005304,-.025456,
-.009644,-.024149,
-.0123,-.02291,
-.01742,-.02803,
-.012288,-.030629,
-.006783,-.032298,
-.001071,-.032985,
.004673,-.03267,
.010275,-.031362,
.015565,-.029101,
.01742,-.02803,
.0123,-.02291,
180.*
4,1,15,-.02291,-.0123,
-.024698,-.008135,
-.025735,-.003723,
-.025991,.000803,
-.025456,.005304,
-.024149,.009644,
-.02291,.0123,
-.02803,.01742,
-.030629,.012288,
-.032298,.006783,
-.032985,.001071,
-.03267,-.004673,
-.031362,-.010275,
-.029101,-.015565,
-.02803,-.01742,
-.02291,-.0123,
180.*
4,1,15,-.0123,.02291,
-.008135,.024698,
-.003723,.025735,
.000803,.025991,
.005304,.025456,
.009644,.024149,
.0123,.02291,
.01742,.02803,
.012288,.030629,
.006783,.032298,
.001071,.032985,
-.004673,.03267,
-.010275,.031362,
-.015565,.029101,
-.01742,.02803,
-.0123,.02291,
180.*
%
%ADD33MACRO33*%
%AMMACRO26*
4,1,15,.02401,.0134,
.025972,.009027,
.027145,.00438,
.027493,-.0004,
.027006,-.005168,
.025698,-.009779,
.02401,-.0134,
.02912,-.01851,
.031892,-.013172,
.033695,-.007434,
.034474,-.00147,
.034205,.004538,
.032897,.010409,
.03059,.015964,
.02912,.01851,
.02401,.0134,
270.*
4,1,15,.0134,-.02401,
.009027,-.025972,
.00438,-.027145,
-.0004,-.027493,
-.005168,-.027006,
-.009779,-.025698,
-.0134,-.02401,
-.01851,-.02912,
-.013172,-.031892,
-.007434,-.033695,
-.00147,-.034474,
.004538,-.034205,
.010409,-.032897,
.015964,-.03059,
.01851,-.02912,
.0134,-.02401,
270.*
4,1,15,-.02401,-.0134,
-.025972,-.009027,
-.027145,-.00438,
-.027493,.0004,
-.027006,.005168,
-.025698,.009779,
-.02401,.0134,
-.02912,.01851,
-.031892,.013172,
-.033695,.007434,
-.034474,.00147,
-.034205,-.004538,
-.032897,-.010409,
-.03059,-.015964,
-.02912,-.01851,
-.02401,-.0134,
270.*
4,1,15,-.0134,.02401,
-.009027,.025972,
-.00438,.027145,
.0004,.027493,
.005168,.027006,
.009779,.025698,
.0134,.02401,
.01851,.02912,
.013172,.031892,
.007434,.033695,
.00147,.034474,
-.004538,.034205,
-.010409,.032897,
-.015964,.03059,
-.01851,.02912,
-.0134,.02401,
270.*
%
%ADD26MACRO26*%
%AMMACRO21*
4,1,17,.03056,.01996,
.033562,.01435,
.035544,.008304,
.036446,.002006,
.03624,-.004353,
.034934,-.01058,
.032566,-.016486,
.03056,-.01996,
.0356,-.025,
.0394,-.018438,
.042004,-.011316,
.043331,-.003851,
.043341,.003732,
.042034,.011201,
.039451,.018331,
.035668,.024903,
.0356,.025,
.03056,.01996,
270.*
4,1,17,.01996,-.03056,
.01435,-.033562,
.008304,-.035544,
.002006,-.036446,
-.004353,-.03624,
-.01058,-.034934,
-.016486,-.032566,
-.01996,-.03056,
-.025,-.0356,
-.018438,-.0394,
-.011316,-.042004,
-.003851,-.043331,
.003732,-.043341,
.011201,-.042034,
.018331,-.039451,
.024903,-.035668,
.025,-.0356,
.01996,-.03056,
270.*
4,1,17,-.03056,-.01996,
-.033562,-.01435,
-.035544,-.008304,
-.036446,-.002006,
-.03624,.004353,
-.034934,.01058,
-.032566,.016486,
-.03056,.01996,
-.0356,.025,
-.0394,.018438,
-.042004,.011316,
-.043331,.003851,
-.043341,-.003732,
-.042034,-.011201,
-.039451,-.018331,
-.035668,-.024903,
-.0356,-.025,
-.03056,-.01996,
270.*
4,1,17,-.01996,.03056,
-.01435,.033562,
-.008304,.035544,
-.002006,.036446,
.004353,.03624,
.01058,.034934,
.016486,.032566,
.01996,.03056,
.025,.0356,
.018438,.0394,
.011316,.042004,
.003851,.043331,
-.003732,.043341,
-.011201,.042034,
-.018331,.039451,
-.024903,.035668,
-.025,.0356,
-.01996,.03056,
270.*
%
%ADD21MACRO21*%
%AMMACRO23*
4,1,17,.03273,.02212,
.036074,.0161,
.038322,.009592,
.039405,.002791,
.039291,-.004094,
.037983,-.010854,
.035521,-.017285,
.03273,-.02212,
.03775,-.02715,
.041891,-.020182,
.044759,-.012601,
.046267,-.004638,
.04637,.003467,
.045063,.011466,
.042388,.019117,
.038424,.026188,
.03775,.02715,
.03273,.02212,
270.*
4,1,17,.02212,-.03273,
.0161,-.036074,
.009592,-.038322,
.002791,-.039405,
-.004094,-.039291,
-.010854,-.037983,
-.017285,-.035521,
-.02212,-.03273,
-.02715,-.03775,
-.020182,-.041891,
-.012601,-.044759,
-.004638,-.046267,
.003467,-.04637,
.011466,-.045063,
.019117,-.042388,
.026188,-.038424,
.02715,-.03775,
.02212,-.03273,
270.*
4,1,17,-.03273,-.02212,
-.036074,-.0161,
-.038322,-.009592,
-.039405,-.002791,
-.039291,.004094,
-.037983,.010854,
-.035521,.017285,
-.03273,.02212,
-.03775,.02715,
-.041891,.020182,
-.044759,.012601,
-.046267,.004638,
-.04637,-.003467,
-.045063,-.011466,
-.042388,-.019117,
-.038424,-.026188,
-.03775,-.02715,
-.03273,-.02212,
270.*
4,1,17,-.02212,.03273,
-.0161,.036074,
-.009592,.038322,
-.002791,.039405,
.004094,.039291,
.010854,.037983,
.017285,.035521,
.02212,.03273,
.02715,.03775,
.020182,.041891,
.012601,.044759,
.004638,.046267,
-.003467,.04637,
-.011466,.045063,
-.019117,.042388,
-.026188,.038424,
-.02715,.03775,
-.02212,.03273,
270.*
%
%ADD23MACRO23*%
%ADD38C,.006*%
%ADD41C,.08409*%
%ADD43C,.24506*%
%ADD39C,.16406*%
%ADD45C,.13266*%
%ADD44C,.35606*%
%ADD40C,.15806*%
%ADD42C,.19786*%
G75*
%LPD*%
G75*
G36*
G01X-723776Y-489221D02*
X1782976D01*
Y2987387D01*
X-723776D01*
Y-489221D01*
G37*
%LPC*%
G75*
G36*
G01X5906Y17752D02*
G02X2004Y21654I0J3902D01*
G01Y2064961D01*
G02X5905Y2068862I3901J0D01*
G01X92520D01*
G03X100429Y2076772I-1J7910D01*
G01Y2080709D01*
G02X104331Y2084610I3902J-1D01*
G01X397638D01*
G02X403508Y2078740I0J-5870D01*
G01Y7874D01*
G02X397638Y2004I-5870J0D01*
G01X104331D01*
G02X100429Y5906I0J3902D01*
G01Y9843D01*
G03X92520Y17752I-7909J0D01*
G01X5906D01*
G37*
%LPD*%
G75*
G36*
G01X17980Y1347510D02*
Y1348455D01*
X17981D01*
G02X22973Y1348450I2490J-5857D01*
G01X22974D01*
Y1347505D01*
G03X23213Y1347078I500J0D01*
G02X23859Y1346612I-2741J-4480D01*
G01X25411D01*
X25412Y1346611D01*
G02X14107Y1342598I-4940J-4013D01*
G02X15507Y1346580I6365J-1D01*
G01X17048D01*
G02X17740Y1347083I3424J-3982D01*
G03X17980Y1347510I-260J427D01*
G37*
G36*
G01X17976Y989245D02*
Y990190D01*
X17977D01*
G02X22969Y990185I2490J-5857D01*
G01X22970D01*
Y989240D01*
G03X23209Y988813I500J0D01*
G02X23856Y988346I-2741J-4480D01*
G01X25408D01*
G02X14103Y984333I-4940J-4013D01*
G02X15503Y988316I6365J0D01*
G01X17045D01*
G02X17736Y988818I3422J-3984D01*
G03X17976Y989245I-260J427D01*
G37*
G36*
G01X170004Y727205D02*
G02X156767Y727182I-6619J0D01*
G02X169983Y727726I6618J30D01*
G02X169986Y727689I-6594J-553D01*
G02X170004Y727205I-6600J-488D01*
G37*
G36*
G01Y552205D02*
G02X156767Y552182I-6619J0D01*
G02X169983Y552726I6618J30D01*
G02X169986Y552689I-6594J-553D01*
G02X170004Y552205I-6600J-488D01*
G37*
G36*
G01X169982Y1952727D02*
G02X170003Y1952205I-6597J-527D01*
G02X156766I-6618J0D01*
G02X169982Y1952727I6618J0D01*
G37*
G36*
G01X294833Y1881121D02*
X294834Y1885021D01*
G02X307086Y1897273I12252J0D01*
G02X319338Y1885021I0J-12252D01*
G01Y1881121D01*
G02X307086Y1868869I-12252J0D01*
G01Y1868868D01*
G02X294833Y1881121I0J12253D01*
G37*
G36*
G01X169982Y1777727D02*
G02X170003Y1777205I-6597J-527D01*
G02X156766I-6618J0D01*
G02X169982Y1777727I6618J0D01*
G37*
G36*
G01Y1602727D02*
G02X170003Y1602205I-6597J-527D01*
G02X156766I-6618J0D01*
G02X169982Y1602727I6618J0D01*
G37*
G36*
G01Y1427727D02*
G02X170003Y1427205I-6597J-527D01*
G02X156766I-6618J0D01*
G02X169982Y1427727I6618J0D01*
G37*
G36*
G01Y1252727D02*
G02X170003Y1252205I-6597J-527D01*
G02X156766I-6618J0D01*
G02X169982Y1252727I6618J0D01*
G37*
G36*
G01Y1077727D02*
G02X170003Y1077205I-6597J-527D01*
G02X156766I-6618J0D01*
G02X169982Y1077727I6618J0D01*
G37*
G36*
G01X26828Y1054605D02*
G02X20471Y1060962I-6357J0D01*
G01Y1060963D01*
X20472D01*
G02X26828Y1054605I-1J-6357D01*
G37*
G36*
G01X169982Y902727D02*
G02X170003Y902205I-6597J-527D01*
G02X156766I-6618J0D01*
G02X169982Y902727I6618J0D01*
G37*
G36*
G01Y377727D02*
G02X170002Y377205I-6597J-514D01*
G02X156766I-6618J0D01*
G02X169982Y377727I6618J0D01*
G37*
G36*
G01Y202727D02*
G02X170002Y202205I-6597J-514D01*
G02X156766I-6618J0D01*
G02X169982Y202727I6618J0D01*
G37*
G36*
G01Y27727D02*
G02X170002Y27205I-6597J-514D01*
G02X156766I-6618J0D01*
G02X169982Y27727I6618J0D01*
G37*
G54D41*
X30473Y102007D03*
Y137440D03*
X30197Y305027D03*
Y352271D03*
X30473Y1855008D03*
Y1890441D03*
Y1937007D03*
Y1972440D03*
Y2012007D03*
Y2047440D03*
G54D43*
X307086Y308267D03*
G54D39*
X29979Y30500D03*
Y75500D03*
Y166500D03*
Y211500D03*
Y239500D03*
Y284500D03*
Y375500D03*
Y420500D03*
G54D45*
X373385Y32520D03*
Y207520D03*
Y382520D03*
X373386Y557520D03*
Y732520D03*
X373385Y907520D03*
Y1082520D03*
Y1257520D03*
Y1432520D03*
Y1607520D03*
Y1782520D03*
Y1957520D03*
G54D44*
X359842Y78780D03*
Y253780D03*
Y428779D03*
Y603779D03*
Y778780D03*
Y953780D03*
Y1128779D03*
Y1303780D03*
Y1478780D03*
Y1653780D03*
Y1828779D03*
Y2003780D03*
G54D40*
X30254Y514500D03*
Y559500D03*
Y1572504D03*
Y1617504D03*
G54D42*
X65354Y114960D03*
Y464960D03*
Y814960D03*
Y1164960D03*
Y1514960D03*
Y1864960D03*
X307086Y127165D03*
Y477165D03*
Y827165D03*
Y1343504D03*
Y1693504D03*
X307087Y2043503D03*
G54D24*
X48433Y866179D03*
X48467Y869278D03*
X49441Y1238962D03*
X45581Y1278420D03*
X45413Y1283724D03*
X45244Y1289067D03*
X45350Y1299697D03*
X45267Y1294203D03*
X45281Y1310893D03*
X45244Y1305787D03*
X46980Y1335843D03*
Y1325843D03*
Y1315843D03*
Y1320843D03*
Y1330843D03*
Y1345843D03*
Y1340843D03*
X57124Y675327D03*
X54483Y679810D03*
X59236Y670758D03*
X70865Y872278D03*
Y866278D03*
Y860278D03*
Y897750D03*
Y890116D03*
X60815Y1019026D03*
X63577Y1019115D03*
X59127Y1257647D03*
X58356Y1279812D03*
X58416Y1272383D03*
X61866Y1309190D03*
X54543Y1308995D03*
X67568Y1307829D03*
X70340Y1328203D03*
X61866Y1342104D03*
X93223Y417736D03*
X94347Y421562D03*
X96308Y696622D03*
X95775Y751469D03*
X89338Y878294D03*
X91733Y899382D03*
X92633Y907404D03*
X91294Y926951D03*
X98139Y990959D03*
X76446Y1014871D03*
X79499D03*
X82763Y1060051D03*
X96684Y1081791D03*
X96510Y1395382D03*
X95236Y1453321D03*
X80376Y1772098D03*
Y1768566D03*
Y1775609D03*
X106958Y26285D03*
X101430Y41803D03*
X107405Y49898D03*
X107037Y34687D03*
X104350Y62293D03*
X107263Y72244D03*
X109054Y58250D03*
X108672Y86150D03*
X106836Y376461D03*
X106709Y391219D03*
X105451Y406795D03*
X114498Y396207D03*
X109475Y434743D03*
X111017Y419566D03*
X102960Y672823D03*
X113018Y706356D03*
X107025Y725368D03*
X105087Y754126D03*
X106935Y745139D03*
X107173Y735219D03*
X112836Y769122D03*
X111967Y795261D03*
X115139Y849240D03*
X105395Y972040D03*
X102611Y972220D03*
X100687Y999391D03*
X107351Y1093484D03*
X107235Y1081791D03*
X107215Y1072208D03*
X108779Y1105760D03*
X105152Y1118381D03*
X112503Y1115860D03*
X108468Y1129286D03*
X100719Y1312810D03*
Y1306810D03*
Y1330810D03*
Y1336810D03*
Y1324810D03*
Y1318810D03*
Y1346065D03*
X106962Y1434041D03*
X106921Y1419492D03*
X106763Y1444599D03*
X107006Y1452651D03*
X108574Y1463389D03*
X113518Y1489571D03*
X107355Y1770437D03*
X107391Y1794460D03*
X107220Y1791589D03*
X107373Y1780544D03*
X108819Y1812118D03*
X106819Y1802230D03*
X108819Y1824470D03*
X144878Y1738861D03*
X157558Y51426D03*
X161339Y88108D03*
X159417Y91281D03*
X158901Y85017D03*
X168975Y265783D03*
X165975D03*
X168975Y296140D03*
Y286803D03*
Y276298D03*
X165975D03*
Y286803D03*
Y296140D03*
X168975Y312307D03*
Y303868D03*
X165975D03*
Y312307D03*
X156865Y401207D03*
X161517Y436119D03*
X159019Y439268D03*
X158807Y432969D03*
X157272Y604773D03*
X160272D03*
X157272Y633416D03*
Y613574D03*
Y624079D03*
X160272D03*
Y613574D03*
Y633416D03*
X157272Y641144D03*
Y649583D03*
X160272D03*
Y641144D03*
X156610Y751063D03*
X158956Y780982D03*
X161479Y784141D03*
X159053Y787280D03*
X163699Y972924D03*
X166699D03*
X163699Y983439D03*
Y993944D03*
X166699D03*
Y983439D03*
X163424Y1011298D03*
Y1003570D03*
Y1019737D03*
X166424D03*
Y1003570D03*
Y1011298D03*
X156854Y1101031D03*
X159382Y1136151D03*
X158456Y1129045D03*
X158749Y1307733D03*
X155749D03*
X158749Y1328753D03*
Y1318248D03*
X155749D03*
Y1328753D03*
X158749Y1354257D03*
Y1338090D03*
Y1345818D03*
X155749D03*
Y1338090D03*
Y1354257D03*
X158618Y1399448D03*
X164037Y1400226D03*
X170351Y1401324D03*
X159192Y1451105D03*
X159216Y1477124D03*
X159526Y1483434D03*
X161492Y1667763D03*
Y1657248D03*
X158492D03*
Y1667763D03*
X161492Y1695333D03*
Y1687605D03*
Y1678268D03*
X158492D03*
Y1687605D03*
Y1695333D03*
X161492Y1703772D03*
X158492D03*
X163257Y1737619D03*
X150309Y1737009D03*
X168151Y1739208D03*
X165782Y1732903D03*
X156183Y1735240D03*
X156452Y1800821D03*
X161844Y1828225D03*
X159822Y1831380D03*
X159075Y1825087D03*
X175989Y944537D03*
X176011Y936829D03*
X175359Y963486D03*
X175561Y955964D03*
X175135Y972490D03*
X175022Y980281D03*
X175742Y989958D03*
X175449Y997660D03*
X175698Y1008730D03*
X175473Y1016296D03*
X175448Y1031766D03*
X175897Y1023997D03*
X176083Y1402321D03*
X173394Y1736051D03*
X217732Y153964D03*
Y170131D03*
Y161692D03*
Y164692D03*
Y173131D03*
Y156964D03*
X219214Y1287272D03*
Y1301975D03*
X219349Y1308924D03*
X219214Y1294491D03*
X219178Y1324285D03*
Y1332321D03*
Y1316842D03*
Y1339840D03*
X238741Y153964D03*
X227700D03*
X238741Y170131D03*
Y161692D03*
X227700Y170131D03*
Y161692D03*
Y164692D03*
Y173131D03*
X238741Y164692D03*
Y173131D03*
X227700Y156964D03*
X238741D03*
X239746Y407393D03*
Y396878D03*
Y417898D03*
Y399878D03*
Y410393D03*
Y420898D03*
X234012Y754782D03*
X237012D03*
X234012Y762510D03*
Y770949D03*
X237012D03*
Y762510D03*
X241396Y862887D03*
Y855159D03*
Y871326D03*
X238396D03*
Y855159D03*
Y862887D03*
X235709Y1124900D03*
Y1135415D03*
X232709D03*
Y1124900D03*
X242677Y1135415D03*
Y1124900D03*
X235709Y1145920D03*
X232709D03*
X242677D03*
X226642Y1287272D03*
X222214D03*
X229642D03*
X226642Y1301975D03*
X235465D03*
X226777Y1308924D03*
X235600D03*
X242961Y1301975D03*
X243096Y1308924D03*
X226642Y1294491D03*
X235465D03*
X242961D03*
X222214D03*
X222349Y1308924D03*
X222214Y1301975D03*
X238465Y1294491D03*
X229642D03*
X238600Y1308924D03*
X229777D03*
X238465Y1301975D03*
X229642D03*
X226606Y1324285D03*
X235429D03*
X226606Y1332321D03*
X235429D03*
X242925Y1324285D03*
Y1332321D03*
X226606Y1316842D03*
X235429D03*
X242925D03*
X222178D03*
Y1332321D03*
Y1324285D03*
X238429Y1316842D03*
X229606D03*
X238429Y1332321D03*
X229606D03*
X238429Y1324285D03*
X229606D03*
X226606Y1339840D03*
X235429D03*
X242925D03*
X222178D03*
X238429D03*
X229606D03*
X226573Y2031480D03*
X236541D03*
X226573Y2020965D03*
X236541D03*
X242582D03*
Y2031480D03*
X231541Y2020965D03*
X221573D03*
X231541Y2031480D03*
X221573D03*
X226573Y2059050D03*
X236541Y2051322D03*
Y2059050D03*
X226573Y2041985D03*
Y2051322D03*
X236541Y2041985D03*
X242582Y2059050D03*
Y2051322D03*
Y2041985D03*
X231541D03*
X221573Y2051322D03*
Y2041985D03*
X231541Y2059050D03*
Y2051322D03*
X221573Y2059050D03*
X236541Y2067489D03*
X226573D03*
X242582D03*
X221573D03*
X231541D03*
X256566Y54944D03*
X264104D03*
X256566Y45572D03*
X264104D03*
Y48572D03*
X256566D03*
Y65449D03*
X264104D03*
Y57944D03*
X256566D03*
X264104Y68449D03*
X256566D03*
X256947Y128276D03*
X257125Y115559D03*
X256861Y153964D03*
X248083D03*
X256861Y170131D03*
Y161692D03*
X248083Y170131D03*
Y161692D03*
Y164692D03*
Y173131D03*
X256861Y164692D03*
Y173131D03*
X248083Y156964D03*
X256861D03*
X264596Y221664D03*
X252818D03*
X255818D03*
X261596D03*
X264596Y242684D03*
Y232179D03*
X252818Y242684D03*
Y232179D03*
X255818D03*
Y242684D03*
X261596Y232179D03*
Y242684D03*
X264596Y268188D03*
Y259749D03*
Y252021D03*
X252818Y268188D03*
Y252021D03*
Y259749D03*
X255818D03*
Y252021D03*
Y268188D03*
X261596Y252021D03*
Y259749D03*
Y268188D03*
X266040Y407146D03*
Y396631D03*
Y417651D03*
X257572Y396630D03*
Y407145D03*
X248714Y407536D03*
Y397021D03*
X257572Y417650D03*
X248714Y418041D03*
Y400021D03*
Y410536D03*
X257572Y410145D03*
Y399630D03*
X266040Y399631D03*
Y410146D03*
X248714Y421041D03*
X257572Y420650D03*
X266040Y420651D03*
X265722Y463102D03*
X265737Y473680D03*
X267166Y581440D03*
Y572639D03*
X264166D03*
Y581440D03*
X267166Y609010D03*
Y601282D03*
Y591945D03*
X264166D03*
Y601282D03*
Y609010D03*
X267166Y617449D03*
X264166D03*
X243980Y754782D03*
X255021D03*
X258021D03*
X246980D03*
X243980Y762510D03*
Y770949D03*
X255021Y762510D03*
Y770949D03*
X258021D03*
Y762510D03*
X246980Y770949D03*
Y762510D03*
X255837Y823626D03*
X255687Y812192D03*
X253174Y855159D03*
Y862887D03*
Y871326D03*
X250174D03*
Y862887D03*
Y855159D03*
X265766Y949344D03*
X262766D03*
X265766Y967106D03*
Y959859D03*
X265621Y974386D03*
X262621D03*
X262766Y959859D03*
Y967106D03*
X265621Y990553D03*
Y982114D03*
X262621D03*
Y990553D03*
X263473Y1124613D03*
Y1135128D03*
X245677Y1124900D03*
Y1135415D03*
X254433Y1135271D03*
Y1124756D03*
X251433D03*
Y1135271D03*
X260473Y1135128D03*
Y1124613D03*
X263473Y1145633D03*
X245677Y1145920D03*
X254433Y1145776D03*
X251433D03*
X260473Y1145633D03*
X259581Y1272430D03*
Y1282945D03*
X256581D03*
Y1272430D03*
X267622D03*
Y1282945D03*
X245961Y1294491D03*
X246096Y1308924D03*
X245961Y1301975D03*
X259581Y1293450D03*
Y1302787D03*
Y1310515D03*
X256581D03*
Y1302787D03*
Y1293450D03*
X267622Y1310515D03*
Y1302787D03*
Y1293450D03*
X245925Y1316842D03*
Y1332321D03*
Y1324285D03*
X259581Y1318954D03*
X256581D03*
X267622D03*
X245925Y1339840D03*
X260939Y1548010D03*
Y1534139D03*
Y1541055D03*
X263939D03*
Y1534139D03*
Y1548010D03*
X258564Y1621823D03*
X261564D03*
X258564Y1642843D03*
Y1632338D03*
X261564D03*
Y1642843D03*
X258564Y1668347D03*
Y1659908D03*
Y1652180D03*
X261564D03*
Y1659908D03*
Y1668347D03*
X262759Y1697613D03*
Y1676593D03*
Y1687108D03*
X251718Y1697613D03*
Y1687108D03*
Y1676593D03*
X254718D03*
Y1687108D03*
X265759D03*
Y1676593D03*
X254718Y1697613D03*
X265759D03*
X262498Y1722140D03*
X262759Y1714678D03*
Y1706950D03*
X251457Y1722140D03*
X251718Y1714678D03*
Y1706950D03*
X265759D03*
X254718D03*
Y1714678D03*
X265759D03*
X265498Y1722140D03*
X254457D03*
X261639Y1819074D03*
Y1812119D03*
Y1805203D03*
X253468Y1819074D03*
Y1812119D03*
Y1805203D03*
X267396Y1812122D03*
Y1805206D03*
Y1819077D03*
X250468Y1805203D03*
Y1812119D03*
Y1819074D03*
X258639Y1805203D03*
Y1812119D03*
Y1819074D03*
X261459Y1826219D03*
X253288D03*
X261459Y1840090D03*
Y1833135D03*
X253288D03*
Y1840090D03*
X250288D03*
Y1833135D03*
X267037Y1840093D03*
Y1833138D03*
X258459Y1833135D03*
Y1840090D03*
X267037Y1826222D03*
X250288Y1826219D03*
X258459D03*
X247582Y2031480D03*
Y2020965D03*
X260337D03*
Y2031480D03*
X267115Y2020965D03*
Y2031480D03*
X255337D03*
Y2020965D03*
X247582Y2041985D03*
Y2051322D03*
Y2059050D03*
X260337Y2051322D03*
Y2059050D03*
Y2041985D03*
X267115D03*
Y2059050D03*
Y2051322D03*
X255337Y2041985D03*
Y2059050D03*
Y2051322D03*
X260337Y2067489D03*
X247582D03*
X267115D03*
X255337D03*
X288102Y54944D03*
Y45572D03*
X271572Y54944D03*
X279754D03*
X271572Y45572D03*
X279754D03*
Y48572D03*
X271572D03*
X288102D03*
Y65449D03*
X271572D03*
X279754D03*
Y57944D03*
X271572D03*
X288102D03*
X279754Y68449D03*
X271572D03*
X288102D03*
X274531Y407289D03*
Y396774D03*
Y417794D03*
Y399774D03*
Y410289D03*
Y420794D03*
X289569Y532762D03*
Y516595D03*
Y524323D03*
X278944Y581440D03*
Y572639D03*
X275944D03*
Y581440D03*
X278944Y601282D03*
Y609010D03*
Y591945D03*
X275944D03*
Y609010D03*
Y601282D03*
X278944Y617449D03*
X275944D03*
X277544Y949344D03*
X274544D03*
X277544Y967106D03*
Y959859D03*
X277399Y974386D03*
X274399D03*
X274544Y959859D03*
Y967106D03*
X277399Y990553D03*
Y982114D03*
X274399D03*
Y990553D03*
X272821Y1124471D03*
Y1134986D03*
X269821D03*
Y1124471D03*
X272821Y1145491D03*
X269821D03*
X284182Y1184455D03*
Y1192183D03*
X287182D03*
Y1184455D03*
X284182Y1200622D03*
X287182D03*
X270622Y1282945D03*
Y1272430D03*
Y1293450D03*
Y1302787D03*
Y1310515D03*
Y1318954D03*
X275400Y1548190D03*
X268534Y1548010D03*
X282995Y1548190D03*
X275400Y1534319D03*
Y1541235D03*
X268534Y1534139D03*
Y1541055D03*
X282995Y1534319D03*
Y1541235D03*
X285995D03*
Y1534319D03*
X271534Y1541055D03*
Y1534139D03*
X278400Y1541235D03*
Y1534319D03*
X285995Y1548190D03*
X271534Y1548010D03*
X278400Y1548190D03*
X270342Y1621823D03*
X273342D03*
X270342Y1642843D03*
Y1632338D03*
X273342D03*
Y1642843D03*
X270342Y1668347D03*
Y1652180D03*
Y1659908D03*
X273342D03*
Y1652180D03*
Y1668347D03*
X270396Y1819077D03*
Y1805206D03*
Y1812122D03*
X270037Y1826222D03*
Y1833138D03*
Y1840093D03*
X280240Y1858668D03*
X279976Y1864565D03*
X272115Y2031480D03*
Y2020965D03*
Y2051322D03*
Y2059050D03*
Y2041985D03*
Y2067489D03*
X308057Y248863D03*
X306267Y241010D03*
X314914Y238162D03*
X314940Y252083D03*
X300537Y516309D03*
X307966Y516419D03*
Y524147D03*
X300537Y524037D03*
Y532476D03*
X307966Y532586D03*
X292569Y524323D03*
Y516595D03*
Y532762D03*
X304966Y532586D03*
X297537Y532476D03*
Y524037D03*
X304966Y524147D03*
Y516419D03*
X297537Y516309D03*
X313791Y532871D03*
Y516704D03*
Y524432D03*
X315187Y652457D03*
X304146D03*
X307146D03*
X315187Y661258D03*
X304146D03*
Y681100D03*
X315187D03*
Y671763D03*
X304146D03*
X307146D03*
Y681100D03*
Y661258D03*
X315187Y688828D03*
X304146D03*
Y697267D03*
X315187D03*
X307146D03*
Y688828D03*
X310194Y1020657D03*
X310078Y1007303D03*
X310274Y1001286D03*
X310143Y1014094D03*
X307143D03*
X307274Y1001286D03*
X307078Y1007303D03*
X307194Y1020657D03*
X310129Y1027081D03*
X309999Y1033718D03*
X306999D03*
X307129Y1027081D03*
X309678Y1053262D03*
X312527Y1162266D03*
X309159Y1184526D03*
Y1192254D03*
X300691Y1184526D03*
X292721Y1184312D03*
Y1192040D03*
X300691Y1192254D03*
X303691D03*
X295721Y1192040D03*
Y1184312D03*
X303691Y1184526D03*
X312159Y1192254D03*
Y1184526D03*
X312698Y1172804D03*
X309159Y1200693D03*
X300691D03*
X292721Y1200479D03*
X295721D03*
X303691Y1200693D03*
X312159D03*
X314183Y1403423D03*
X312823Y1472957D03*
X312464Y1480102D03*
X312823Y1466002D03*
Y1459086D03*
X295715Y1480099D03*
X295895Y1472954D03*
X304066D03*
X303886Y1480099D03*
X295895Y1459083D03*
Y1465999D03*
X304066D03*
Y1459083D03*
X301066D03*
Y1465999D03*
X292895D03*
Y1459083D03*
X300886Y1480099D03*
X301066Y1472954D03*
X292895D03*
X292715Y1480099D03*
X309823Y1459086D03*
Y1466002D03*
X309464Y1480102D03*
X309823Y1472957D03*
X312464Y1493973D03*
Y1487018D03*
X295715Y1487015D03*
Y1493970D03*
X303886D03*
Y1487015D03*
X300886D03*
Y1493970D03*
X292715D03*
Y1487015D03*
X309464Y1487018D03*
Y1493973D03*
X302267Y1524401D03*
X301734Y1513883D03*
X312077Y1575871D03*
X292614Y1864565D03*
X295754Y1917148D03*
X303349D03*
X295754Y1910232D03*
X303349D03*
X310215Y1910412D03*
X314810D03*
X307215D03*
X300349Y1910232D03*
X292754D03*
X300349Y1917148D03*
X292754D03*
X310215Y1917328D03*
X295754Y1924103D03*
X303349D03*
X310215Y1924283D03*
X307215D03*
X314810D03*
X300349Y1924103D03*
X292754D03*
X307215Y1917328D03*
X314810D03*
X331403Y51409D03*
X333889Y56021D03*
X338227Y61559D03*
X320372Y225979D03*
X318088Y231820D03*
X321899Y238137D03*
X331046Y232021D03*
X320961Y250105D03*
X324709Y231580D03*
X332775Y318634D03*
X332693Y311980D03*
X329693D03*
X329775Y318634D03*
X332775Y335272D03*
Y342461D03*
Y325935D03*
X329775D03*
Y342461D03*
Y335272D03*
X332685Y348655D03*
X329685D03*
X335522Y404033D03*
X323313Y418313D03*
X326196Y413982D03*
X328950Y409216D03*
X320980Y423225D03*
X325139Y516632D03*
Y524360D03*
X316791Y524432D03*
Y516704D03*
Y532871D03*
X325139Y532799D03*
X322139D03*
Y524360D03*
Y516632D03*
X336617Y577978D03*
X319305Y582111D03*
X329636Y584715D03*
X317724Y588250D03*
X337387Y586230D03*
X320380Y576491D03*
X331867Y589810D03*
X333750Y595326D03*
X321742Y599041D03*
X318187Y652457D03*
Y671763D03*
Y681100D03*
Y661258D03*
Y697267D03*
Y688828D03*
X331568Y752967D03*
X339012Y752859D03*
X329336Y762693D03*
X334010Y758588D03*
X327524Y758020D03*
X329938Y948756D03*
X332527Y943746D03*
X324098Y946104D03*
X318557Y941178D03*
X323868Y929978D03*
X326646Y939788D03*
X336160Y937262D03*
X328583Y933262D03*
X321425Y951577D03*
X321235Y1020657D03*
X321315Y1001286D03*
X321119Y1007303D03*
X321184Y1014094D03*
X318184D03*
X318119Y1007303D03*
X318315Y1001286D03*
X318235Y1020657D03*
X321170Y1027081D03*
X321040Y1033718D03*
X318040D03*
X318170Y1027081D03*
X324246Y1051786D03*
X335677Y1048904D03*
X317592Y1053050D03*
X337509Y1109598D03*
X328989Y1121090D03*
X326558Y1126368D03*
X317936Y1192253D03*
Y1184525D03*
X320936D03*
Y1192253D03*
X323403Y1172804D03*
X317936Y1200692D03*
X320936D03*
X327452Y1279447D03*
X321978Y1282086D03*
X329619Y1284016D03*
X327932Y1289221D03*
X325636Y1399114D03*
X334646Y1400804D03*
X323720Y1570924D03*
X333474Y1566686D03*
X335963Y1573797D03*
X323813Y1753231D03*
X329887Y1752081D03*
X317810Y1910412D03*
X332399Y1926787D03*
X317810Y1917328D03*
Y1924283D03*
X359931Y52189D03*
X348289Y50863D03*
X345089Y56190D03*
X340373Y51579D03*
X343816Y318634D03*
X343734Y311980D03*
X340734D03*
X340816Y318634D03*
X343816Y335272D03*
Y342461D03*
Y325935D03*
X340816D03*
Y342461D03*
Y335272D03*
X362236Y324983D03*
X343726Y348655D03*
X340726D03*
X342097Y401684D03*
X363825Y401768D03*
X342900Y580126D03*
X356559Y675167D03*
X362577Y752783D03*
X344109Y751809D03*
X343656Y933725D03*
X345578Y1047844D03*
X344099Y1106798D03*
X344130Y1401670D03*
X350690Y1403243D03*
X348710Y1570187D03*
X361011Y1568890D03*
X343402Y1572080D03*
X348245Y1575241D03*
X355364Y1570990D03*
X345537Y1916558D03*
X344402Y1911123D03*
X363361Y1918313D03*
X358318Y1920680D03*
X363411Y1923459D03*
X340336Y1922409D03*
X372204Y56126D03*
X379257Y52158D03*
X387524Y76847D03*
X374442Y406857D03*
X374542Y401282D03*
X368907Y404308D03*
X376654Y754748D03*
X382892Y767710D03*
X386790Y774338D03*
X379335Y1189778D03*
X383276Y1184136D03*
X386816Y1179841D03*
X376472Y1194999D03*
X373674Y1199967D03*
X371523Y1204725D03*
X374681Y1365620D03*
X367829Y1566108D03*
X366306Y1899864D03*
X374431Y1901397D03*
X374775Y1919243D03*
X379403Y1917261D03*
X369748Y1921795D03*
G54D34*
X253385Y21890D03*
Y32520D03*
X263385Y21890D03*
Y32520D03*
X253385Y196890D03*
X263385D03*
X253385Y207520D03*
X263385D03*
X253385Y371890D03*
X263385D03*
X253385Y382520D03*
X263385D03*
X253386Y546890D03*
Y557520D03*
X263386Y546890D03*
Y557520D03*
X253386Y721890D03*
Y732520D03*
X263386Y721890D03*
Y732520D03*
X253385Y896890D03*
X263385D03*
X253385Y907520D03*
X263385D03*
X253385Y1071890D03*
X263385D03*
X253385Y1082520D03*
X263385D03*
X253385Y1246890D03*
Y1257520D03*
X263385Y1246890D03*
Y1257520D03*
X253385Y1421890D03*
Y1432520D03*
X263385Y1421890D03*
Y1432520D03*
X253385Y1596890D03*
X263385D03*
X253385Y1607520D03*
X263385D03*
X253385Y1771890D03*
X263385D03*
X253385Y1782520D03*
X263385D03*
X253385Y1946890D03*
Y1957520D03*
X263385Y1946890D03*
Y1957520D03*
X273385Y21890D03*
Y32520D03*
X283385Y21890D03*
Y32520D03*
X273385Y196890D03*
X283385D03*
X273385Y207520D03*
X283385D03*
X273385Y371890D03*
X283385D03*
X273385Y382520D03*
X283385D03*
X273386Y546890D03*
Y557520D03*
X283386Y546890D03*
Y557520D03*
X273386Y721890D03*
Y732520D03*
X283386Y721890D03*
Y732520D03*
X273385Y896890D03*
X283385D03*
X273385Y907520D03*
X283385D03*
X273385Y1071890D03*
X283385D03*
X273385Y1082520D03*
X283385D03*
X273385Y1246890D03*
Y1257520D03*
X283385Y1246890D03*
Y1257520D03*
X273385Y1421890D03*
Y1432520D03*
X283385Y1421890D03*
Y1432520D03*
X273385Y1596890D03*
X283385D03*
X273385Y1607520D03*
X283385D03*
X273385Y1771890D03*
X283385D03*
X273385Y1782520D03*
X283385D03*
X273385Y1946890D03*
Y1957520D03*
X283385Y1946890D03*
Y1957520D03*
X293385Y21890D03*
Y32520D03*
X303385Y21890D03*
Y32520D03*
X313385D03*
Y21890D03*
X293385Y196890D03*
X303385D03*
X313385D03*
X293385Y207520D03*
X303385D03*
X313385D03*
X293385Y371890D03*
X303385D03*
X313385D03*
X293385Y382520D03*
X303385D03*
X313385D03*
X293386Y546890D03*
Y557520D03*
X303386Y546890D03*
Y557520D03*
X313386D03*
Y546890D03*
X293386Y721890D03*
Y732520D03*
X303386Y721890D03*
Y732520D03*
X313386D03*
Y721890D03*
X293385Y896890D03*
X303385D03*
X313385D03*
X293385Y907520D03*
X303385D03*
X313385D03*
X293385Y1071890D03*
X303385D03*
X313385D03*
X293385Y1082520D03*
X303385D03*
X313385D03*
X293385Y1246890D03*
Y1257520D03*
X303385Y1246890D03*
Y1257520D03*
X313385D03*
Y1246890D03*
X293385Y1421890D03*
Y1432520D03*
X303385Y1421890D03*
Y1432520D03*
X313385D03*
Y1421890D03*
X293385Y1596890D03*
X303385D03*
X313385D03*
X293385Y1607520D03*
X303385D03*
X313385D03*
X293385Y1771890D03*
X303385D03*
X313385D03*
X293385Y1782520D03*
X303385D03*
X313385D03*
X293385Y1946890D03*
Y1957520D03*
X303385Y1946890D03*
Y1957520D03*
X313385D03*
Y1946890D03*
X337165Y24705D03*
X323385Y32520D03*
Y21890D03*
X337165Y34705D03*
Y199705D03*
X323385Y196890D03*
X337165Y209705D03*
X323385Y207520D03*
Y371890D03*
X337165Y374705D03*
Y384705D03*
X323385Y382520D03*
X337166Y549705D03*
Y559705D03*
X323386Y557520D03*
Y546890D03*
X337166Y724705D03*
X323386Y732520D03*
Y721890D03*
X337166Y734705D03*
X337165Y899705D03*
X323385Y896890D03*
X337165Y909705D03*
X323385Y907520D03*
Y1071890D03*
X337165Y1074705D03*
Y1084705D03*
X323385Y1082520D03*
X337165Y1249705D03*
Y1259705D03*
X323385Y1257520D03*
Y1246890D03*
X337165Y1424705D03*
Y1434705D03*
X323385Y1432520D03*
Y1421890D03*
X337165Y1599705D03*
X323385Y1596890D03*
X337165Y1609705D03*
X323385Y1607520D03*
Y1771890D03*
X337165Y1774705D03*
Y1784705D03*
X323385Y1782520D03*
X337165Y1949705D03*
Y1959705D03*
X323385Y1957520D03*
Y1946890D03*
X342165Y19705D03*
Y29705D03*
X347165Y24705D03*
X352165Y19705D03*
Y29705D03*
X357165Y24705D03*
X362165Y19705D03*
Y29705D03*
X347165Y34705D03*
X357165D03*
X342165Y194705D03*
X347165Y199705D03*
X352165Y194705D03*
X357165Y199705D03*
X362165Y194705D03*
X342165Y204705D03*
X347165Y209705D03*
X352165Y204705D03*
X357165Y209705D03*
X362165Y204705D03*
X342165Y369705D03*
X352165D03*
X362165D03*
X342165Y379705D03*
X347165Y374705D03*
Y384705D03*
X352165Y379705D03*
X357165Y374705D03*
Y384705D03*
X362165Y379705D03*
X342166Y544705D03*
Y554705D03*
X347166Y549705D03*
Y559705D03*
X352166Y544705D03*
Y554705D03*
X357166Y549705D03*
Y559705D03*
X362166Y544705D03*
Y554705D03*
X342166Y719705D03*
Y729705D03*
X347166Y724705D03*
X352166Y719705D03*
Y729705D03*
X357166Y724705D03*
X362166Y719705D03*
Y729705D03*
X347166Y734705D03*
X357166D03*
X342165Y894705D03*
X347165Y899705D03*
X352165Y894705D03*
X357165Y899705D03*
X362165Y894705D03*
X342165Y904705D03*
X347165Y909705D03*
X352165Y904705D03*
X357165Y909705D03*
X362165Y904705D03*
X342165Y1069705D03*
X352165D03*
X362165D03*
X342165Y1079705D03*
X347165Y1074705D03*
Y1084705D03*
X352165Y1079705D03*
X357165Y1074705D03*
Y1084705D03*
X362165Y1079705D03*
X342165Y1244705D03*
Y1254705D03*
X347165Y1249705D03*
Y1259705D03*
X352165Y1244705D03*
Y1254705D03*
X357165Y1249705D03*
Y1259705D03*
X362165Y1244705D03*
Y1254705D03*
X342165Y1419705D03*
Y1429705D03*
X347165Y1424705D03*
Y1434705D03*
X352165Y1419705D03*
Y1429705D03*
X357165Y1424705D03*
Y1434705D03*
X362165Y1419705D03*
Y1429705D03*
X342165Y1594705D03*
X347165Y1599705D03*
X352165Y1594705D03*
X357165Y1599705D03*
X362165Y1594705D03*
X342165Y1604705D03*
X347165Y1609705D03*
X352165Y1604705D03*
X357165Y1609705D03*
X362165Y1604705D03*
X342165Y1769705D03*
X352165D03*
X362165D03*
X342165Y1779705D03*
X347165Y1774705D03*
Y1784705D03*
X352165Y1779705D03*
X357165Y1774705D03*
Y1784705D03*
X362165Y1779705D03*
X342165Y1944705D03*
Y1954705D03*
X347165Y1949705D03*
Y1959705D03*
X352165Y1944705D03*
Y1954705D03*
X357165Y1949705D03*
Y1959705D03*
X362165Y1944705D03*
Y1954705D03*
G54D27*
X65354Y101180D03*
X55511Y105117D03*
X51574Y114960D03*
X55511Y124803D03*
X65354Y128740D03*
Y451180D03*
X55511Y455117D03*
X51574Y464960D03*
X55511Y474803D03*
X65354Y478740D03*
Y801180D03*
X55511Y805117D03*
X51574Y814960D03*
X55511Y824803D03*
X65354Y828740D03*
Y1151180D03*
X55511Y1155117D03*
X51574Y1164960D03*
X55511Y1174803D03*
X65354Y1178740D03*
Y1501180D03*
X55511Y1505117D03*
X51574Y1514960D03*
X55511Y1524803D03*
X65354Y1528740D03*
Y1851180D03*
X55511Y1855117D03*
X51574Y1864960D03*
X55511Y1874803D03*
X65354Y1878740D03*
X75197Y105117D03*
Y124803D03*
X79134Y114960D03*
Y464960D03*
X75197Y455117D03*
Y474803D03*
Y805117D03*
Y824803D03*
X79134Y814960D03*
Y1164960D03*
X75197Y1155117D03*
Y1174803D03*
Y1505117D03*
Y1524803D03*
X79134Y1514960D03*
Y1864960D03*
X75197Y1855117D03*
Y1874803D03*
X307086Y113385D03*
X297243Y117322D03*
X293306Y127165D03*
X297243Y137008D03*
X307086Y140945D03*
Y463385D03*
X297243Y467322D03*
X293306Y477165D03*
X297243Y487008D03*
X307086Y490945D03*
Y813385D03*
X297243Y817322D03*
X293306Y827165D03*
X297243Y837008D03*
X307086Y840945D03*
Y1329724D03*
X297243Y1333661D03*
X293306Y1343504D03*
X297243Y1353347D03*
X307086Y1357284D03*
Y1679724D03*
X297243Y1683661D03*
X293306Y1693504D03*
X297243Y1703347D03*
X307086Y1707284D03*
X307087Y2029723D03*
X297244Y2033660D03*
X293307Y2043503D03*
X297244Y2053346D03*
X307087Y2057283D03*
X320866Y127165D03*
X316929Y117322D03*
Y137008D03*
Y467322D03*
Y487008D03*
X320866Y477165D03*
Y827165D03*
X316929Y817322D03*
Y837008D03*
Y1333661D03*
Y1353347D03*
X320866Y1343504D03*
Y1693504D03*
X316929Y1683661D03*
Y1703347D03*
X316930Y2033660D03*
Y2053346D03*
X320867Y2043503D03*
G54D13*
X22756Y125629D03*
X22480Y328649D03*
X22756Y1878630D03*
Y1960629D03*
Y2035629D03*
G54D22*
X30473Y102007D03*
Y137440D03*
X30197Y305027D03*
Y352271D03*
X30473Y1855008D03*
Y1890441D03*
Y1937007D03*
Y1972440D03*
Y2012007D03*
Y2047440D03*
G54D29*
X119920Y18071D03*
Y28071D03*
Y38071D03*
Y48071D03*
Y58071D03*
Y68071D03*
Y78071D03*
Y88071D03*
Y218071D03*
Y228071D03*
Y238071D03*
Y248071D03*
Y258071D03*
Y268071D03*
Y278071D03*
Y288071D03*
Y298071D03*
Y308071D03*
Y318071D03*
Y328071D03*
Y366102D03*
Y376102D03*
Y386102D03*
Y396102D03*
Y406102D03*
Y416102D03*
Y426102D03*
Y436102D03*
Y566102D03*
Y576102D03*
Y586102D03*
Y596102D03*
Y606102D03*
Y616102D03*
Y626102D03*
Y636102D03*
Y646102D03*
Y656102D03*
Y666102D03*
Y676102D03*
Y714134D03*
Y724134D03*
Y734134D03*
Y744134D03*
Y754134D03*
Y764134D03*
Y774134D03*
Y784134D03*
Y914134D03*
Y924134D03*
Y934134D03*
Y944134D03*
Y954134D03*
Y964134D03*
Y974134D03*
Y984134D03*
Y994134D03*
Y1004134D03*
Y1014134D03*
Y1024134D03*
Y1062165D03*
Y1072165D03*
Y1082165D03*
Y1092165D03*
Y1102165D03*
Y1112165D03*
Y1122165D03*
Y1132165D03*
Y1262165D03*
Y1272165D03*
Y1282165D03*
Y1292165D03*
Y1302165D03*
Y1312165D03*
Y1322165D03*
Y1332165D03*
Y1342165D03*
Y1352165D03*
Y1362165D03*
Y1372165D03*
Y1410197D03*
Y1420197D03*
Y1430197D03*
Y1440197D03*
Y1450197D03*
Y1460197D03*
Y1470197D03*
Y1480197D03*
Y1610197D03*
Y1620197D03*
Y1630197D03*
Y1640197D03*
Y1650197D03*
Y1660197D03*
Y1670197D03*
Y1680197D03*
Y1690197D03*
Y1700197D03*
Y1710197D03*
Y1720197D03*
Y1758228D03*
Y1768228D03*
Y1778228D03*
Y1788228D03*
Y1798228D03*
Y1808228D03*
Y1818228D03*
Y1828228D03*
Y1958228D03*
Y1968228D03*
Y1978228D03*
Y1988228D03*
Y1998228D03*
Y2008228D03*
Y2018228D03*
Y2028228D03*
Y2038228D03*
Y2048228D03*
Y2058228D03*
Y2068228D03*
X139920Y28071D03*
Y18071D03*
Y58071D03*
Y48071D03*
Y38071D03*
Y78071D03*
Y68071D03*
Y88071D03*
Y228071D03*
Y218071D03*
Y248071D03*
Y238071D03*
Y268071D03*
Y258071D03*
Y298071D03*
Y288071D03*
Y278071D03*
Y318071D03*
Y308071D03*
Y328071D03*
Y366102D03*
Y396102D03*
Y386102D03*
Y376102D03*
Y416102D03*
Y406102D03*
Y436102D03*
Y426102D03*
Y566102D03*
Y586102D03*
Y576102D03*
Y606102D03*
Y596102D03*
Y636102D03*
Y626102D03*
Y616102D03*
Y656102D03*
Y646102D03*
Y676102D03*
Y666102D03*
Y734134D03*
Y724134D03*
Y714134D03*
Y754134D03*
Y744134D03*
Y774134D03*
Y764134D03*
Y784134D03*
Y924134D03*
Y914134D03*
Y944134D03*
Y934134D03*
Y974134D03*
Y964134D03*
Y954134D03*
Y994134D03*
Y984134D03*
Y1024134D03*
Y1014134D03*
Y1004134D03*
Y1072165D03*
Y1062165D03*
Y1092165D03*
Y1082165D03*
Y1122165D03*
Y1112165D03*
Y1102165D03*
Y1132165D03*
Y1262165D03*
Y1282165D03*
Y1272165D03*
Y1312165D03*
Y1302165D03*
Y1292165D03*
Y1332165D03*
Y1322165D03*
Y1362165D03*
Y1352165D03*
Y1342165D03*
Y1372165D03*
Y1410197D03*
Y1430197D03*
Y1420197D03*
Y1460197D03*
Y1450197D03*
Y1440197D03*
Y1480197D03*
Y1470197D03*
Y1620197D03*
Y1610197D03*
Y1650197D03*
Y1640197D03*
Y1630197D03*
Y1670197D03*
Y1660197D03*
Y1700197D03*
Y1690197D03*
Y1680197D03*
Y1720197D03*
Y1710197D03*
Y1768228D03*
Y1758228D03*
Y1798228D03*
Y1788228D03*
Y1778228D03*
Y1818228D03*
Y1808228D03*
Y1828228D03*
Y1958228D03*
Y1988228D03*
Y1978228D03*
Y1968228D03*
Y2008228D03*
Y1998228D03*
Y2038228D03*
Y2028228D03*
Y2018228D03*
Y2058228D03*
Y2048228D03*
Y2068228D03*
G54D14*
X14073Y512197D03*
Y522000D03*
Y552000D03*
Y561803D03*
Y1580004D03*
Y1570201D03*
Y1610004D03*
Y1619807D03*
X65254Y519500D03*
Y529500D03*
Y539500D03*
X55254Y524500D03*
Y534500D03*
X65254Y549500D03*
X55254Y544500D03*
Y554500D03*
X65254Y1577504D03*
Y1587504D03*
Y1597504D03*
X55254Y1582504D03*
Y1592504D03*
Y1602504D03*
X65254Y1607504D03*
X55254Y1612504D03*
X203542Y73105D03*
X204069Y152050D03*
X204137Y247568D03*
X204597Y331786D03*
X203541Y421732D03*
X204333Y506517D03*
X206668Y598130D03*
X204596Y681645D03*
X205626Y774526D03*
X205386Y856244D03*
X210091Y947202D03*
X209296Y1032544D03*
X205030Y1122856D03*
X205122Y1206233D03*
X205626Y1299104D03*
X204332Y1380966D03*
X203243Y1474162D03*
X204859Y1557277D03*
X205923Y1648177D03*
X205387Y1731351D03*
X205310Y1823227D03*
X204069Y1900420D03*
X205905Y1998730D03*
X205310Y2043388D03*
G54D17*
X15547Y707364D03*
X25389D03*
X7673Y703427D03*
X15547Y715238D03*
Y730986D03*
X25389Y715238D03*
Y730986D03*
X7673Y711301D03*
Y719175D03*
Y727049D03*
X15547Y738860D03*
Y754608D03*
X25389Y738860D03*
Y754608D03*
X7673Y742797D03*
Y750671D03*
Y758545D03*
X15547Y762483D03*
Y770357D03*
Y778231D03*
X25389Y762483D03*
Y770357D03*
Y778231D03*
X7673Y774293D03*
Y782167D03*
X15547Y786105D03*
Y801853D03*
X25389Y786105D03*
Y801853D03*
X7673Y790041D03*
Y797915D03*
Y805790D03*
X15547Y809727D03*
Y817601D03*
X25389Y809727D03*
Y817601D03*
X7673Y813664D03*
Y821538D03*
Y829412D03*
X15547Y833349D03*
Y841223D03*
Y849097D03*
X25389Y833349D03*
Y841223D03*
Y849097D03*
X7673Y837286D03*
Y845160D03*
X15547Y856971D03*
Y872719D03*
X25389Y856971D03*
Y864845D03*
X7673Y860908D03*
Y868782D03*
Y876656D03*
X15547Y880593D03*
Y888467D03*
Y896341D03*
X25389Y880593D03*
Y888467D03*
Y896341D03*
X7673Y892404D03*
Y900278D03*
X15547Y912089D03*
Y919963D03*
X25389Y904215D03*
Y919963D03*
X7673Y908152D03*
Y916026D03*
X15547Y927837D03*
Y935711D03*
Y951459D03*
X25389Y927837D03*
Y935711D03*
Y943585D03*
X7673Y931774D03*
Y939648D03*
Y947522D03*
X15547Y959333D03*
Y967207D03*
Y975081D03*
X25389Y959333D03*
Y967207D03*
Y975081D03*
X7673Y955396D03*
Y971144D03*
Y979018D03*
Y994766D03*
X15547Y990829D03*
X25389D03*
Y998703D03*
X7673Y1002640D03*
Y1010514D03*
X15547Y1006577D03*
Y1014451D03*
Y1022325D03*
X25389Y1014451D03*
Y1022325D03*
X7673Y1026262D03*
X15551Y1065629D03*
X25393D03*
X7677Y1061692D03*
X15551Y1073503D03*
Y1081377D03*
X25393D03*
Y1089251D03*
X7677Y1077440D03*
Y1085314D03*
Y1093188D03*
X15551Y1097125D03*
Y1104999D03*
Y1112873D03*
Y1120748D03*
X25393Y1097125D03*
Y1104999D03*
Y1120748D03*
X7677Y1101062D03*
Y1116810D03*
X15551Y1136496D03*
Y1144370D03*
X25393Y1128622D03*
Y1136496D03*
Y1144370D03*
X7677Y1124684D03*
Y1132558D03*
Y1140432D03*
X15551Y1152244D03*
Y1160118D03*
X25393D03*
Y1167992D03*
X7677Y1156180D03*
Y1164055D03*
X15551Y1175866D03*
Y1183740D03*
Y1191614D03*
X25393Y1175866D03*
Y1183740D03*
X7677Y1171929D03*
Y1179803D03*
X15551Y1199488D03*
Y1215236D03*
X25393Y1199488D03*
Y1207362D03*
Y1215236D03*
X7677Y1195551D03*
Y1203425D03*
Y1211299D03*
X15551Y1223110D03*
Y1230984D03*
Y1238858D03*
X25393Y1223110D03*
Y1238858D03*
X7677Y1219173D03*
Y1234921D03*
X15551Y1254606D03*
Y1262480D03*
X25393Y1246732D03*
Y1254606D03*
X7677Y1242795D03*
Y1250669D03*
Y1258543D03*
X15551Y1270354D03*
Y1278228D03*
Y1286102D03*
X25393Y1278228D03*
X7677Y1274291D03*
X15551Y1293976D03*
Y1301850D03*
Y1309724D03*
X25393Y1293976D03*
Y1301850D03*
Y1309724D03*
X7677Y1290039D03*
Y1297913D03*
Y1305787D03*
X15551Y1317598D03*
Y1325472D03*
Y1333346D03*
X25393Y1325472D03*
Y1333346D03*
X7677Y1321535D03*
Y1329409D03*
Y1337283D03*
Y1353031D03*
X15551Y1349094D03*
X25393D03*
Y1356968D03*
X7677Y1368779D03*
Y1384527D03*
X15551Y1372716D03*
Y1380590D03*
X25393Y1364842D03*
Y1380590D03*
Y1388464D03*
X33263Y703427D03*
Y711301D03*
Y719175D03*
Y727049D03*
Y742797D03*
Y750671D03*
Y758545D03*
Y774293D03*
Y782167D03*
Y790041D03*
Y797915D03*
Y805790D03*
Y813664D03*
Y821538D03*
Y829412D03*
Y837286D03*
Y845160D03*
Y860908D03*
Y868782D03*
Y876656D03*
Y884530D03*
Y900278D03*
Y908152D03*
Y916026D03*
Y923900D03*
Y939648D03*
Y947522D03*
Y955396D03*
Y963270D03*
Y979018D03*
Y994766D03*
Y1002640D03*
Y1010514D03*
Y1026262D03*
X33267Y1061692D03*
Y1069566D03*
Y1077440D03*
Y1085314D03*
Y1101062D03*
Y1108936D03*
Y1116810D03*
Y1124684D03*
Y1140432D03*
Y1148306D03*
Y1156180D03*
Y1164055D03*
Y1179803D03*
Y1187677D03*
Y1195551D03*
Y1203425D03*
Y1219173D03*
Y1227047D03*
Y1234921D03*
Y1242795D03*
Y1258543D03*
Y1266417D03*
Y1274291D03*
Y1282165D03*
Y1290039D03*
Y1297913D03*
Y1305787D03*
Y1313661D03*
Y1321535D03*
Y1329409D03*
Y1337283D03*
Y1353031D03*
Y1368779D03*
Y1376653D03*
G54D16*
X13441Y495961D03*
X11153Y1638435D03*
X16552Y1638005D03*
X267420Y147540D03*
X263086Y147675D03*
X264516Y497341D03*
X264181Y847354D03*
X267194Y1191777D03*
X262559D03*
X276523Y147585D03*
X271943Y147630D03*
X285513Y322688D03*
X281074D03*
X289895D03*
X277776Y497341D03*
X273405D03*
X268938D03*
X274514Y672192D03*
X270109D03*
X283340D03*
X278955D03*
X268686Y847488D03*
X277788Y847237D03*
X273305D03*
X285666Y1016162D03*
X281124D03*
X290107D03*
X276807Y1191777D03*
X272082D03*
X284240Y1374544D03*
X279518Y1374543D03*
X275052Y1374715D03*
X270579Y1374626D03*
X291054Y1543211D03*
X279703Y1723398D03*
X284583Y1723465D03*
X289499Y1723735D03*
X287121Y1898327D03*
X282717D03*
X278262D03*
X273817D03*
X294506Y322688D03*
X294617Y1016162D03*
X304870Y1543211D03*
X300392D03*
X295675D03*
G54D20*
X23402Y1668874D03*
Y1718480D03*
Y1768087D03*
Y1817693D03*
X45056Y1668874D03*
Y1685410D03*
Y1701945D03*
Y1718480D03*
Y1735016D03*
Y1751551D03*
Y1768087D03*
Y1784622D03*
Y1817693D03*
Y1801158D03*
G54D25*
X64979Y35500D03*
Y45500D03*
X54979Y40500D03*
X64979Y65500D03*
X54979Y60500D03*
Y70500D03*
X64979Y171500D03*
X54979Y176500D03*
X64979Y181500D03*
Y201500D03*
X54979Y196500D03*
Y206500D03*
X64979Y244500D03*
X54979Y249500D03*
X64979Y254500D03*
Y264500D03*
Y274500D03*
X54979Y269500D03*
Y279500D03*
X64979Y380500D03*
Y390500D03*
X54979Y385500D03*
X64979Y400500D03*
Y410500D03*
X54979Y405500D03*
Y415500D03*
G54D12*
X22756Y113818D03*
X22480Y316838D03*
Y340460D03*
X22756Y1866819D03*
Y1948818D03*
Y2023818D03*
G54D36*
X307086Y1883071D03*
G54D18*
X20468Y696341D03*
Y984333D03*
X20472Y1054606D03*
Y1342598D03*
G54D10*
X29979Y30500D03*
Y75500D03*
Y166500D03*
Y211500D03*
Y239500D03*
Y284500D03*
Y375500D03*
Y420500D03*
G54D35*
X307086Y308267D03*
G54D15*
X30254Y514500D03*
Y559500D03*
Y1572504D03*
Y1617504D03*
G54D31*
X163385Y27205D03*
Y202205D03*
Y377205D03*
X163386Y552205D03*
Y727205D03*
X163385Y902205D03*
Y1077205D03*
Y1252205D03*
Y1427205D03*
Y1602205D03*
Y1777205D03*
Y1952205D03*
X373385Y32520D03*
Y207520D03*
Y382520D03*
X373386Y557520D03*
Y732520D03*
X373385Y907520D03*
Y1082520D03*
Y1257520D03*
Y1432520D03*
Y1607520D03*
Y1782520D03*
Y1957520D03*
G54D37*
X359842Y78780D03*
Y253780D03*
Y428779D03*
Y603779D03*
Y778780D03*
Y953780D03*
Y1128779D03*
Y1303780D03*
Y1478780D03*
Y1653780D03*
Y1828779D03*
Y2003780D03*
G54D19*
X15547Y723112D03*
X25389D03*
X15547Y746734D03*
X25389D03*
X7673Y734923D03*
Y766419D03*
X15547Y793979D03*
X25389D03*
X15547Y825475D03*
X25389D03*
X7673Y853034D03*
X15547Y864845D03*
X25389Y872719D03*
X7673Y884530D03*
X15547Y904215D03*
X25389Y912089D03*
X7673Y923900D03*
X15547Y943585D03*
X25389Y951459D03*
X7673Y963270D03*
X15547Y998703D03*
X7673Y1018388D03*
X25389Y1006577D03*
X15547Y1030199D03*
X25389D03*
X7677Y1069566D03*
X15551Y1089251D03*
X25393Y1073503D03*
Y1112873D03*
X7677Y1108936D03*
X15551Y1128622D03*
Y1167992D03*
X25393Y1152244D03*
X7677Y1148306D03*
X25393Y1191614D03*
X7677Y1187677D03*
X15551Y1207362D03*
X25393Y1230984D03*
X7677Y1227047D03*
X15551Y1246732D03*
X25393Y1262480D03*
Y1270354D03*
Y1286102D03*
X7677Y1266417D03*
Y1282165D03*
Y1313661D03*
X25393Y1317598D03*
X7677Y1360905D03*
X15551Y1356968D03*
X7677Y1376653D03*
X15551Y1364842D03*
X25393Y1372716D03*
X15551Y1388464D03*
X33263Y734923D03*
Y766419D03*
Y853034D03*
Y892404D03*
Y931774D03*
Y971144D03*
Y1018388D03*
X33267Y1093188D03*
Y1132558D03*
Y1171929D03*
Y1211299D03*
Y1250669D03*
Y1360905D03*
Y1384527D03*
G54D32*
X173385Y32520D03*
Y21890D03*
X183385Y32520D03*
Y21890D03*
X193385Y32520D03*
Y21890D03*
X173385Y196890D03*
X183385D03*
X193385D03*
X173385Y207520D03*
X183385D03*
X193385D03*
X173385Y371890D03*
X183385D03*
X193385D03*
X173385Y382520D03*
X183385D03*
X193385D03*
X173386Y557520D03*
Y546890D03*
X183386Y557520D03*
Y546890D03*
X193386Y557520D03*
Y546890D03*
X173386Y732520D03*
Y721890D03*
X183386Y732520D03*
Y721890D03*
X193386Y732520D03*
Y721890D03*
X173385Y896890D03*
X183385D03*
X193385D03*
X173385Y907520D03*
X183385D03*
X193385D03*
X173385Y1071890D03*
X183385D03*
X193385D03*
X173385Y1082520D03*
X183385D03*
X193385D03*
X173385Y1257520D03*
Y1246890D03*
X183385Y1257520D03*
Y1246890D03*
X193385Y1257520D03*
Y1246890D03*
X173385Y1432520D03*
Y1421890D03*
X183385Y1432520D03*
Y1421890D03*
X193385Y1432520D03*
Y1421890D03*
X173385Y1596890D03*
X183385D03*
X193385D03*
X173385Y1607520D03*
X183385D03*
X193385D03*
X173385Y1771890D03*
X183385D03*
X193385D03*
X173385Y1782520D03*
X183385D03*
X193385D03*
X173385Y1957520D03*
Y1946890D03*
X183385Y1957520D03*
Y1946890D03*
X193385Y1957520D03*
Y1946890D03*
X203385Y32520D03*
Y21890D03*
X213385Y32520D03*
Y21890D03*
X203385Y196890D03*
X213385D03*
X203385Y207520D03*
X213385D03*
X203385Y371890D03*
X213385D03*
X203385Y382520D03*
X213385D03*
X203386Y557520D03*
Y546890D03*
X213386Y557520D03*
Y546890D03*
X203386Y732520D03*
Y721890D03*
X213386Y732520D03*
Y721890D03*
X203385Y896890D03*
X213385D03*
X203385Y907520D03*
X213385D03*
X203385Y1071890D03*
X213385D03*
X203385Y1082520D03*
X213385D03*
X203385Y1257520D03*
Y1246890D03*
X213385Y1257520D03*
Y1246890D03*
X203385Y1432520D03*
Y1421890D03*
X213385Y1432520D03*
Y1421890D03*
X203385Y1596890D03*
X213385D03*
X203385Y1607520D03*
X213385D03*
X203385Y1771890D03*
X213385D03*
X203385Y1782520D03*
X213385D03*
X203385Y1957520D03*
Y1946890D03*
X213385Y1957520D03*
Y1946890D03*
X223385Y32520D03*
Y21890D03*
X233385Y32520D03*
Y21890D03*
X243385Y32520D03*
Y21890D03*
X223385Y196890D03*
X233385D03*
X243385D03*
X223385Y207520D03*
X233385D03*
X243385D03*
X223385Y371890D03*
X233385D03*
X243385D03*
X223385Y382520D03*
X233385D03*
X243385D03*
X223386Y557520D03*
Y546890D03*
X233386Y557520D03*
Y546890D03*
X243386Y557520D03*
Y546890D03*
X223386Y732520D03*
Y721890D03*
X233386Y732520D03*
Y721890D03*
X243386Y732520D03*
Y721890D03*
X223385Y896890D03*
X233385D03*
X243385D03*
X223385Y907520D03*
X233385D03*
X243385D03*
X223385Y1071890D03*
X233385D03*
X243385D03*
X223385Y1082520D03*
X233385D03*
X243385D03*
X223385Y1257520D03*
Y1246890D03*
X233385Y1257520D03*
Y1246890D03*
X243385Y1257520D03*
Y1246890D03*
X223385Y1432520D03*
Y1421890D03*
X233385Y1432520D03*
Y1421890D03*
X243385Y1432520D03*
Y1421890D03*
X223385Y1596890D03*
X233385D03*
X243385D03*
X223385Y1607520D03*
X233385D03*
X243385D03*
X223385Y1771890D03*
X233385D03*
X243385D03*
X223385Y1782520D03*
X233385D03*
X243385D03*
X223385Y1957520D03*
Y1946890D03*
X233385Y1957520D03*
Y1946890D03*
X243385Y1957520D03*
Y1946890D03*
G54D28*
X65354Y114960D03*
Y464960D03*
Y814960D03*
Y1164960D03*
Y1514960D03*
Y1864960D03*
X307086Y127165D03*
Y477165D03*
Y827165D03*
Y1343504D03*
Y1693504D03*
X307087Y2043503D03*
G54D11*
X25219Y18752D03*
X3001Y52034D03*
Y100034D03*
Y150034D03*
Y200034D03*
Y250034D03*
Y300034D03*
Y350034D03*
Y400034D03*
Y450034D03*
Y500034D03*
Y550034D03*
X10914Y578848D03*
X15984Y578849D03*
X3001Y600034D03*
Y650034D03*
Y700034D03*
Y750034D03*
Y800034D03*
Y850034D03*
Y900034D03*
Y950034D03*
Y1000034D03*
Y1050034D03*
Y1100034D03*
Y1150034D03*
Y1200034D03*
Y1250034D03*
Y1300034D03*
Y1350034D03*
Y1400034D03*
Y1450034D03*
Y1500034D03*
Y1550034D03*
X11541Y1562330D03*
X3006Y1594602D03*
X3012Y1610165D03*
X3001Y1650034D03*
Y1700034D03*
Y1750034D03*
Y1800034D03*
Y1850034D03*
Y1900034D03*
Y1950034D03*
Y2000034D03*
Y2050034D03*
X26833Y2067866D03*
X61888Y666012D03*
X57458Y1253378D03*
X54543Y1296513D03*
X63061Y1296312D03*
X67568Y1296654D03*
X54130Y1313763D03*
X55544Y1770835D03*
X55080Y1762982D03*
X54948Y1755171D03*
X56425Y1778371D03*
X70376Y1796383D03*
X75219Y18752D03*
X97417Y32853D03*
Y37438D03*
X97536Y376580D03*
X97457Y371909D03*
X97985Y391220D03*
X97643Y396024D03*
X86187Y680710D03*
X79520Y682439D03*
X88681Y704108D03*
X81563Y705437D03*
X86673Y685710D03*
X79536D03*
X98591Y720745D03*
X98564Y715937D03*
X97443Y739962D03*
X97534Y735248D03*
X98124Y745139D03*
X96904Y1067515D03*
X96948Y1092036D03*
X96949Y1087095D03*
X96774Y1072226D03*
X97403Y1424340D03*
X97825Y1419492D03*
X96993Y1443743D03*
X96996Y1438980D03*
X97465Y1447919D03*
X88837Y1771103D03*
X91460Y1765062D03*
X93771Y1748227D03*
X75376Y1796236D03*
X80376Y1796163D03*
X85376Y1796236D03*
X76833Y2067866D03*
X106335Y22580D03*
X108082Y38899D03*
X102646Y49461D03*
X104116Y82557D03*
X101990Y426104D03*
X101244Y774100D03*
X98652Y1096403D03*
X105684Y1125919D03*
X105455Y1472894D03*
X99103Y1765722D03*
X99068Y1760827D03*
X99047Y1785571D03*
X98873Y1780542D03*
X99294Y1789947D03*
X105669Y1815227D03*
X109991Y2083607D03*
X125219Y3002D03*
X162384Y56744D03*
X161742Y72497D03*
X162586Y68130D03*
X169500Y126110D03*
Y118626D03*
Y111407D03*
X166500D03*
Y118626D03*
Y126110D03*
X169329Y140623D03*
X169500Y132705D03*
X169329Y148066D03*
X166329D03*
X166500Y132705D03*
X166329Y140623D03*
X169329Y156102D03*
Y163621D03*
X166329D03*
Y156102D03*
X161377Y407575D03*
X161257Y420869D03*
X159430Y461714D03*
X156430D03*
X159430Y483012D03*
X159259Y490930D03*
X159430Y468933D03*
Y476417D03*
X156430D03*
Y468933D03*
X156259Y490930D03*
X156430Y483012D03*
X159259Y513928D03*
Y498373D03*
Y506409D03*
X156259D03*
Y498373D03*
Y513928D03*
X161826Y756757D03*
X161131Y774878D03*
X161644Y764231D03*
X158444Y822725D03*
X165872D03*
X162872D03*
X155444D03*
X165872Y830209D03*
X158444D03*
X165872Y836804D03*
X158444D03*
X165701Y844722D03*
X158273D03*
X165701Y852165D03*
X158273D03*
X155273D03*
X162701D03*
X155273Y844722D03*
X162701D03*
X155444Y836804D03*
X162872D03*
X155444Y830209D03*
X162872D03*
X165701Y860201D03*
X158273D03*
X165701Y867720D03*
X158273D03*
X155273D03*
X162701D03*
X155273Y860201D03*
X162701D03*
X164539Y1116135D03*
X162140Y1106853D03*
X156124Y1176256D03*
X163552D03*
Y1183740D03*
Y1190335D03*
X156124D03*
Y1183740D03*
X163552Y1169037D03*
X156124D03*
X153124D03*
X160552D03*
X153124Y1183740D03*
Y1190335D03*
X160552D03*
Y1183740D03*
Y1176256D03*
X153124D03*
X169375Y1183740D03*
Y1190335D03*
Y1176256D03*
X163381Y1198253D03*
X155953D03*
X152953D03*
X160381D03*
X169204D03*
X163099Y1457084D03*
X162524Y1462651D03*
X162242Y1471380D03*
X154109Y1499221D03*
X161537D03*
Y1506440D03*
X170360D03*
X154109D03*
X157109D03*
X164537D03*
Y1499221D03*
X157109D03*
X153938Y1528437D03*
X154109Y1513924D03*
Y1520519D03*
X170360Y1513924D03*
Y1520519D03*
X161537D03*
Y1513924D03*
X161366Y1528437D03*
X170189D03*
X164366D03*
X164537Y1513924D03*
Y1520519D03*
X157109D03*
Y1513924D03*
X156938Y1528437D03*
X153938Y1535880D03*
Y1543916D03*
Y1551435D03*
X170189Y1535880D03*
Y1543916D03*
X161366Y1535880D03*
Y1543916D03*
Y1551435D03*
X170189D03*
X164366D03*
Y1543916D03*
Y1535880D03*
X156938Y1551435D03*
Y1543916D03*
Y1535880D03*
X163250Y1815631D03*
X162140Y1807740D03*
X155091Y1866003D03*
X162519D03*
X159519D03*
X152091D03*
X155091Y1880706D03*
Y1887301D03*
X162519D03*
Y1880706D03*
Y1873222D03*
X155091D03*
X152091D03*
X168342D03*
X159519D03*
Y1880706D03*
Y1887301D03*
X168342D03*
Y1880706D03*
X152091Y1887301D03*
Y1880706D03*
X154920Y1902662D03*
Y1910698D03*
X162348Y1902662D03*
Y1910698D03*
X154920Y1895219D03*
X162348D03*
X168171D03*
X159348D03*
X151920D03*
X159348Y1910698D03*
Y1902662D03*
X168171Y1910698D03*
Y1902662D03*
X151920Y1910698D03*
Y1902662D03*
X154920Y1918217D03*
X162348D03*
X168171D03*
X159348D03*
X151920D03*
X159991Y2083607D03*
X175219Y3002D03*
X176928Y126110D03*
Y118626D03*
Y111407D03*
X173928D03*
Y118626D03*
Y126110D03*
X176757Y140623D03*
X176928Y132705D03*
X176757Y148066D03*
X173757D03*
X173928Y132705D03*
X173757Y140623D03*
X176757Y156102D03*
Y163621D03*
X173757D03*
Y156102D03*
X175033Y261594D03*
Y268813D03*
X178033D03*
Y261594D03*
X175033Y282892D03*
X174862Y290810D03*
Y298253D03*
X175033Y276297D03*
X178033D03*
X177862Y298253D03*
Y290810D03*
X178033Y282892D03*
X174862Y313808D03*
Y306289D03*
X177862D03*
Y313808D03*
X182191Y822725D03*
X174695D03*
X171695D03*
X179191D03*
X174524Y844722D03*
Y852165D03*
X182191Y830209D03*
X174695D03*
X182191Y836804D03*
X174695D03*
X182020Y844722D03*
Y852165D03*
X179020D03*
Y844722D03*
X171695Y836804D03*
X179191D03*
X171695Y830209D03*
X179191D03*
X171524Y852165D03*
Y844722D03*
X174524Y860201D03*
Y867720D03*
X182020Y860201D03*
Y867720D03*
X179020D03*
Y860201D03*
X171524Y867720D03*
Y860201D03*
X184284Y948331D03*
X184196Y967371D03*
X184632Y983423D03*
X184353Y1001556D03*
X184118Y1019280D03*
X188385Y1020810D03*
X179871Y1176256D03*
Y1190335D03*
Y1183740D03*
X172375Y1176256D03*
Y1190335D03*
Y1183740D03*
X176871D03*
Y1190335D03*
Y1176256D03*
X179700Y1198253D03*
X172204D03*
X176700D03*
X177856Y1506440D03*
X173360D03*
X180856D03*
X177856Y1513924D03*
Y1520519D03*
X177685Y1528437D03*
X173189D03*
X173360Y1520519D03*
Y1513924D03*
X180685Y1528437D03*
X180856Y1520519D03*
Y1513924D03*
X177685Y1535880D03*
Y1543916D03*
Y1551435D03*
X173189D03*
Y1543916D03*
Y1535880D03*
X180685Y1551435D03*
Y1543916D03*
Y1535880D03*
X178838Y1880706D03*
Y1887301D03*
Y1873222D03*
X171342Y1880706D03*
Y1887301D03*
Y1873222D03*
X175838D03*
Y1887301D03*
Y1880706D03*
X178667Y1902662D03*
Y1910698D03*
Y1895219D03*
X171171Y1902662D03*
Y1910698D03*
Y1895219D03*
X175667D03*
Y1910698D03*
Y1902662D03*
X178667Y1918217D03*
X171171D03*
X175667D03*
X219131Y1663167D03*
Y1670386D03*
Y1684465D03*
Y1677870D03*
X218960Y1692383D03*
Y1699826D03*
Y1707862D03*
Y1715381D03*
X209991Y2083607D03*
X225219Y3002D03*
X237955Y56999D03*
X240955D03*
X237955Y64483D03*
X237784Y78996D03*
X237955Y71078D03*
X240955D03*
X240784Y78996D03*
X240955Y64483D03*
X237784Y94475D03*
Y101994D03*
Y86439D03*
X240784D03*
Y101994D03*
Y94475D03*
X241033Y244995D03*
X233537D03*
X224714Y237776D03*
Y244995D03*
X227714D03*
Y237776D03*
X236537Y244995D03*
X241033Y259074D03*
X240862Y266992D03*
Y274435D03*
X241033Y252479D03*
X233537Y259074D03*
X233366Y266992D03*
Y274435D03*
X224714Y259074D03*
X224543Y266992D03*
Y274435D03*
X233537Y252479D03*
X224714D03*
X227714D03*
X236537D03*
X227543Y274435D03*
Y266992D03*
X227714Y259074D03*
X236366Y274435D03*
Y266992D03*
X236537Y259074D03*
X240862Y289990D03*
Y282471D03*
X233366Y289990D03*
X224543D03*
X233366Y282471D03*
X224543D03*
X227543D03*
X236366D03*
X227543Y289990D03*
X236366D03*
X229548Y461083D03*
X232548D03*
X238371Y482381D03*
X238200Y490299D03*
X229548Y482381D03*
X229377Y490299D03*
X238371Y468302D03*
Y475786D03*
X229548Y468302D03*
Y475786D03*
X232548D03*
Y468302D03*
X241371Y475786D03*
Y468302D03*
X232377Y490299D03*
X232548Y482381D03*
X241200Y490299D03*
X241371Y482381D03*
X238200Y513297D03*
X229377D03*
X238200Y497742D03*
X229377D03*
X238200Y505778D03*
X229377D03*
X232377D03*
X241200D03*
X232377Y497742D03*
X241200D03*
X232377Y513297D03*
X241200D03*
X227963Y608108D03*
X235391D03*
X227963Y601513D03*
X235391D03*
Y594029D03*
X227963D03*
X230963D03*
X238391D03*
Y601513D03*
X230963D03*
X238391Y608108D03*
X230963D03*
X227792Y631505D03*
X235220D03*
X227792Y623469D03*
X235220D03*
X227792Y616026D03*
X235220D03*
X238220D03*
X230792D03*
X238220Y623469D03*
X230792D03*
X238220Y631505D03*
X230792D03*
X227792Y639024D03*
X235220D03*
X238220D03*
X230792D03*
X231339Y959673D03*
X238767D03*
Y967157D03*
Y973752D03*
X231339D03*
Y967157D03*
X238767Y952454D03*
X231339D03*
X234339D03*
X241767D03*
X234339Y967157D03*
Y973752D03*
X241767D03*
Y967157D03*
Y959673D03*
X234339D03*
X238596Y981670D03*
X231168D03*
X238596Y997149D03*
Y989113D03*
X231168Y997149D03*
Y989113D03*
X234168D03*
Y997149D03*
X241596Y989113D03*
Y997149D03*
X234168Y981670D03*
X241596D03*
X238596Y1004668D03*
X231168D03*
X234168D03*
X241596D03*
X235659Y1215296D03*
X228231D03*
X235659Y1207777D03*
Y1199741D03*
X228231Y1207777D03*
Y1199741D03*
X231231D03*
Y1207777D03*
X238659Y1199741D03*
Y1207777D03*
X231231Y1215296D03*
X238659D03*
X235382Y1670386D03*
X226559Y1663167D03*
Y1670386D03*
X222131D03*
X229559D03*
Y1663167D03*
X238382Y1670386D03*
X222131Y1663167D03*
X242878Y1670386D03*
X235382Y1677870D03*
X235211Y1692383D03*
X235382Y1684465D03*
X226559D03*
Y1677870D03*
X226388Y1692383D03*
X221960D03*
X222131Y1677870D03*
Y1684465D03*
X229388Y1692383D03*
X229559Y1677870D03*
Y1684465D03*
X238382D03*
X238211Y1692383D03*
X238382Y1677870D03*
X242878D03*
Y1684465D03*
X242707Y1692383D03*
X235211Y1699826D03*
X226388D03*
X235211Y1715381D03*
Y1707862D03*
X226388D03*
Y1715381D03*
X221960D03*
Y1707862D03*
X229388Y1715381D03*
Y1707862D03*
X238211D03*
Y1715381D03*
X221960Y1699826D03*
X229388D03*
X238211D03*
X242707D03*
Y1707862D03*
Y1715381D03*
X245451Y56999D03*
X248451D03*
X245451Y64483D03*
X245280Y78996D03*
X245451Y71078D03*
X248451D03*
X248280Y78996D03*
X248451Y64483D03*
X245280Y94475D03*
Y101994D03*
Y86439D03*
X248280D03*
Y101994D03*
Y94475D03*
X267627Y115559D03*
X244033Y244995D03*
Y252479D03*
X243862Y274435D03*
Y266992D03*
X244033Y259074D03*
X243862Y282471D03*
Y289990D03*
X245867Y482381D03*
X245696Y490299D03*
X245867Y468302D03*
Y475786D03*
X248867D03*
Y468302D03*
X248696Y490299D03*
X248867Y482381D03*
X245696Y513297D03*
Y497742D03*
Y505778D03*
X248696D03*
Y497742D03*
Y513297D03*
X251710Y608108D03*
Y601513D03*
Y594029D03*
X244214Y608108D03*
Y601513D03*
Y594029D03*
X247214D03*
Y601513D03*
Y608108D03*
X254710Y594029D03*
Y601513D03*
Y608108D03*
X264433Y624321D03*
X267433D03*
X251539Y631505D03*
Y623469D03*
Y616026D03*
X244043Y631505D03*
Y623469D03*
Y616026D03*
X247043D03*
Y623469D03*
Y631505D03*
X254539Y616026D03*
Y623469D03*
Y631505D03*
X251539Y639024D03*
X244043D03*
X247043D03*
X254539D03*
X255086Y959673D03*
Y973752D03*
Y967157D03*
X247590Y959673D03*
Y973752D03*
Y967157D03*
X250590D03*
Y973752D03*
Y959673D03*
X258086Y967157D03*
Y973752D03*
Y959673D03*
X254915Y981670D03*
Y997149D03*
Y989113D03*
X247419Y981670D03*
Y997149D03*
Y989113D03*
X250419D03*
Y997149D03*
Y981670D03*
X257915Y989113D03*
Y997149D03*
Y981670D03*
X254915Y1004668D03*
X247419D03*
X250419D03*
X257915D03*
X251978Y1215296D03*
X244482D03*
X251978Y1207777D03*
Y1199741D03*
X244482Y1207777D03*
Y1199741D03*
X247482D03*
Y1207777D03*
X254978Y1199741D03*
Y1207777D03*
X247482Y1215296D03*
X254978D03*
X245878Y1670386D03*
X245707Y1692383D03*
X245878Y1684465D03*
Y1677870D03*
X245707Y1715381D03*
Y1707862D03*
Y1699826D03*
X259991Y2083607D03*
X275219Y3002D03*
X271547Y260353D03*
X276617Y256400D03*
X281193Y256624D03*
X281569Y436169D03*
X286665Y432844D03*
X291002D03*
X274991Y463099D03*
X285348Y610540D03*
X290984Y607215D03*
X276044Y624627D03*
X279044D03*
X273114Y785968D03*
X278184Y782643D03*
X282737D03*
X270070Y812192D03*
X285966Y959767D03*
X291194Y956442D03*
X282958Y1134471D03*
X288188Y1131146D03*
X283808Y1308959D03*
X289210Y1305634D03*
X275521Y1479435D03*
X279990D03*
X270234Y1482760D03*
X284086Y1659883D03*
X289421Y1656558D03*
X274704Y1723196D03*
X281066Y1834569D03*
X291550Y1829846D03*
X286623Y1829400D03*
X299687Y78778D03*
X304151D03*
X308651D03*
X313089D03*
X294483Y82732D03*
X295509Y607215D03*
X295874Y956442D03*
X292698Y1131146D03*
X294133Y1305634D03*
X313894Y1513883D03*
X294090Y1656558D03*
X293606Y1858668D03*
X314562Y2009087D03*
X309991Y2083607D03*
X325219Y3002D03*
X322005Y78778D03*
X317567D03*
X325796Y1162266D03*
X324803Y2005272D03*
X320045Y2005215D03*
X361799Y311938D03*
X354000Y652170D03*
X363169Y1329686D03*
X351391D03*
X354391D03*
X363169Y1350706D03*
Y1360043D03*
Y1340201D03*
X351391Y1350706D03*
Y1360043D03*
Y1340201D03*
X354391D03*
Y1360043D03*
Y1350706D03*
X363169Y1376210D03*
Y1367771D03*
X351391Y1376210D03*
Y1367771D03*
X354391D03*
Y1376210D03*
X352337Y1887285D03*
X359991Y2083607D03*
X375219Y3002D03*
X366169Y1329686D03*
Y1340201D03*
Y1360043D03*
Y1350706D03*
X373564Y1352548D03*
X366169Y1367771D03*
Y1376210D03*
X402512Y17108D03*
Y67108D03*
Y117108D03*
Y167108D03*
Y217108D03*
Y267108D03*
Y317108D03*
Y367108D03*
Y417108D03*
Y467108D03*
Y517108D03*
Y567108D03*
Y617108D03*
Y667108D03*
Y717108D03*
Y767108D03*
Y817108D03*
Y867108D03*
Y917108D03*
Y967108D03*
Y1017108D03*
Y1067108D03*
Y1117108D03*
Y1167108D03*
Y1217108D03*
Y1267108D03*
Y1317108D03*
Y1367108D03*
Y1417108D03*
Y1467108D03*
Y1517108D03*
Y1567108D03*
Y1617108D03*
Y1667108D03*
Y1717108D03*
Y1767108D03*
Y1817108D03*
Y1867108D03*
Y1917108D03*
Y1967108D03*
Y2017108D03*
Y2067108D03*
G54D30*
X119920Y98071D03*
Y108071D03*
Y118071D03*
Y128071D03*
Y138071D03*
Y148071D03*
Y158071D03*
Y168071D03*
Y178071D03*
Y188071D03*
Y198071D03*
Y208071D03*
Y446102D03*
Y456102D03*
Y466102D03*
Y476102D03*
Y486102D03*
Y496102D03*
Y506102D03*
Y516102D03*
Y526102D03*
Y536102D03*
Y546102D03*
Y556102D03*
Y794134D03*
Y804134D03*
Y814134D03*
Y824134D03*
Y834134D03*
Y844134D03*
Y854134D03*
Y864134D03*
Y874134D03*
Y884134D03*
Y894134D03*
Y904134D03*
Y1142165D03*
Y1152165D03*
Y1162165D03*
Y1172165D03*
Y1182165D03*
Y1192165D03*
Y1202165D03*
Y1212165D03*
Y1222165D03*
Y1232165D03*
Y1242165D03*
Y1252165D03*
Y1490197D03*
Y1500197D03*
Y1510197D03*
Y1520197D03*
Y1530197D03*
Y1540197D03*
Y1550197D03*
Y1560197D03*
Y1570197D03*
Y1580197D03*
Y1590197D03*
Y1600197D03*
Y1838228D03*
Y1848228D03*
Y1858228D03*
Y1868228D03*
Y1878228D03*
Y1888228D03*
Y1898228D03*
Y1908228D03*
Y1918228D03*
Y1928228D03*
Y1938228D03*
Y1948228D03*
X139920Y98071D03*
Y128071D03*
Y118071D03*
Y108071D03*
Y148071D03*
Y138071D03*
Y178071D03*
Y168071D03*
Y158071D03*
Y198071D03*
Y188071D03*
Y208071D03*
Y466102D03*
Y456102D03*
Y446102D03*
Y486102D03*
Y476102D03*
Y516102D03*
Y506102D03*
Y496102D03*
Y536102D03*
Y526102D03*
Y556102D03*
Y546102D03*
Y804134D03*
Y794134D03*
Y824134D03*
Y814134D03*
Y854134D03*
Y844134D03*
Y834134D03*
Y874134D03*
Y864134D03*
Y904134D03*
Y894134D03*
Y884134D03*
Y1142165D03*
Y1162165D03*
Y1152165D03*
Y1192165D03*
Y1182165D03*
Y1172165D03*
Y1212165D03*
Y1202165D03*
Y1242165D03*
Y1232165D03*
Y1222165D03*
Y1252165D03*
Y1500197D03*
Y1490197D03*
Y1530197D03*
Y1520197D03*
Y1510197D03*
Y1550197D03*
Y1540197D03*
Y1580197D03*
Y1570197D03*
Y1560197D03*
Y1600197D03*
Y1590197D03*
Y1838228D03*
Y1868228D03*
Y1858228D03*
Y1848228D03*
Y1888228D03*
Y1878228D03*
Y1918228D03*
Y1908228D03*
Y1898228D03*
Y1938228D03*
Y1928228D03*
Y1948228D03*
G54D33*
X189762Y73105D03*
X190289Y152050D03*
X190357Y247568D03*
X190817Y331786D03*
X189761Y421732D03*
X190553Y506517D03*
X192888Y598130D03*
X190816Y681645D03*
X191846Y774526D03*
X191606Y856244D03*
X196311Y947202D03*
X195516Y1032544D03*
X191250Y1122856D03*
X191342Y1206233D03*
X191846Y1299104D03*
X190552Y1380966D03*
X189463Y1474162D03*
X191079Y1557277D03*
X192143Y1648177D03*
X191607Y1731351D03*
X191530Y1823227D03*
X190289Y1900420D03*
X192125Y1998730D03*
X191530Y2043388D03*
G54D21*
X23402Y1685410D03*
Y1701945D03*
Y1735016D03*
Y1751551D03*
Y1784622D03*
Y1801158D03*
G54D26*
X64979Y55500D03*
X54979Y50500D03*
X64979Y191500D03*
X54979Y186500D03*
Y259500D03*
Y395500D03*
G54D23*
X45411Y505996D03*
Y568004D03*
Y1564000D03*
Y1626008D03*
%LPC*%
G75*
G54D38*
G01X-723776Y2987387D02*
Y-376795D01*
Y-489221D01*
X1782976D01*
Y-376795D01*
Y2987387D01*
X-723776D01*
G01X-4000Y-62500D02*
Y-137500D01*
X496000D01*
Y-62500D01*
X-4000D01*
G01X8000Y-127500D02*
Y-132500D01*
G01X6543Y-127500D02*
X9457D01*
G01X14367Y-132500D02*
X11833D01*
Y-127500D01*
X14367D01*
G01X13353Y-129917D02*
X11833D01*
G01X16933Y-127500D02*
Y-132500D01*
X19467D01*
G01X23300Y-132667D02*
X23173Y-132583D01*
Y-132417D01*
X23300Y-132333D01*
X23427Y-132417D01*
Y-132583D01*
X23300Y-132667D01*
G01Y-130417D02*
X23173Y-130333D01*
Y-130167D01*
X23300Y-130083D01*
X23427Y-130167D01*
Y-130333D01*
X23300Y-130417D01*
G01X28083Y-134167D02*
X27450Y-133333D01*
X27133Y-132500D01*
Y-129167D01*
X27450Y-128333D01*
X28083Y-127500D01*
G01X33500D02*
X32993Y-127667D01*
X32613Y-128083D01*
X32360Y-128583D01*
X32170Y-129250D01*
X32107Y-130000D01*
X32170Y-130750D01*
X32360Y-131417D01*
X32613Y-131917D01*
X32993Y-132333D01*
X33500Y-132500D01*
X34007Y-132333D01*
X34387Y-131917D01*
X34640Y-131417D01*
X34830Y-130750D01*
X34893Y-130000D01*
X34830Y-129250D01*
X34640Y-128583D01*
X34387Y-128083D01*
X34007Y-127667D01*
X33500Y-127500D01*
G01X37207Y-131500D02*
X37587Y-132083D01*
X38093Y-132417D01*
X38663Y-132500D01*
X39170Y-132417D01*
X39677Y-132000D01*
X39993Y-131500D01*
X40057Y-131000D01*
X39930Y-130417D01*
X39487Y-130000D01*
X39043Y-129833D01*
X38473D01*
G01X39043D02*
X39423Y-129583D01*
X39740Y-129167D01*
X39867Y-128667D01*
X39740Y-128167D01*
X39423Y-127750D01*
X38853Y-127500D01*
X38283Y-127583D01*
X37713Y-127917D01*
G01X44017Y-134167D02*
X44650Y-133333D01*
X44967Y-132500D01*
Y-129167D01*
X44650Y-128333D01*
X44017Y-127500D01*
G01X47407Y-131500D02*
X47787Y-132083D01*
X48293Y-132417D01*
X48863Y-132500D01*
X49370Y-132417D01*
X49877Y-132000D01*
X50193Y-131500D01*
X50257Y-131000D01*
X50130Y-130417D01*
X49687Y-130000D01*
X49243Y-129833D01*
X48673D01*
G01X49243D02*
X49623Y-129583D01*
X49940Y-129167D01*
X50067Y-128667D01*
X49940Y-128167D01*
X49623Y-127750D01*
X49053Y-127500D01*
X48483Y-127583D01*
X47913Y-127917D01*
G01X52697Y-128333D02*
X53077Y-127833D01*
X53520Y-127583D01*
X54027Y-127500D01*
X54660Y-127667D01*
X55103Y-128083D01*
X55230Y-128583D01*
X55167Y-129083D01*
X54913Y-129500D01*
X53647Y-130333D01*
X53077Y-130917D01*
X52697Y-131750D01*
X52570Y-132500D01*
X55230D01*
G01X58873D02*
X59000Y-131417D01*
X59190Y-130500D01*
X59443Y-129667D01*
X59760Y-128750D01*
X60267Y-127500D01*
X57733D01*
G01X63277Y-130833D02*
X64923D01*
G01X67997Y-128333D02*
X68377Y-127833D01*
X68820Y-127583D01*
X69327Y-127500D01*
X69960Y-127667D01*
X70403Y-128083D01*
X70530Y-128583D01*
X70467Y-129083D01*
X70213Y-129500D01*
X68947Y-130333D01*
X68377Y-130917D01*
X67997Y-131750D01*
X67870Y-132500D01*
X70530D01*
G01X72907Y-131500D02*
X73287Y-132083D01*
X73793Y-132417D01*
X74363Y-132500D01*
X74870Y-132417D01*
X75377Y-132000D01*
X75693Y-131500D01*
X75757Y-131000D01*
X75630Y-130417D01*
X75187Y-130000D01*
X74743Y-129833D01*
X74173D01*
G01X74743D02*
X75123Y-129583D01*
X75440Y-129167D01*
X75567Y-128667D01*
X75440Y-128167D01*
X75123Y-127750D01*
X74553Y-127500D01*
X73983Y-127583D01*
X73413Y-127917D01*
G01X80160Y-132500D02*
Y-127500D01*
X77817Y-131083D01*
X80983D01*
G01X83107Y-131750D02*
X83487Y-132167D01*
X83930Y-132417D01*
X84500Y-132500D01*
X85070Y-132333D01*
X85513Y-132000D01*
X85830Y-131417D01*
X85893Y-130750D01*
X85767Y-130083D01*
X85450Y-129667D01*
X85007Y-129333D01*
X84563Y-129250D01*
X84120Y-129333D01*
X83550Y-129667D01*
X83740Y-127500D01*
X85450D01*
G01X93497Y-132500D02*
Y-127500D01*
X95903D01*
G01X95017Y-129917D02*
X93497D01*
G01X98217Y-132500D02*
X99800Y-127500D01*
X101383Y-132500D01*
G01X100813Y-130750D02*
X98787D01*
G01X103570Y-132500D02*
X106230Y-127500D01*
G01X103570D02*
X106230Y-132500D01*
G01X110000Y-132667D02*
X109873Y-132583D01*
Y-132417D01*
X110000Y-132333D01*
X110127Y-132417D01*
Y-132583D01*
X110000Y-132667D01*
G01Y-130417D02*
X109873Y-130333D01*
Y-130167D01*
X110000Y-130083D01*
X110127Y-130167D01*
Y-130333D01*
X110000Y-130417D01*
G01X114783Y-134167D02*
X114150Y-133333D01*
X113833Y-132500D01*
Y-129167D01*
X114150Y-128333D01*
X114783Y-127500D01*
G01X120200D02*
X119693Y-127667D01*
X119313Y-128083D01*
X119060Y-128583D01*
X118870Y-129250D01*
X118807Y-130000D01*
X118870Y-130750D01*
X119060Y-131417D01*
X119313Y-131917D01*
X119693Y-132333D01*
X120200Y-132500D01*
X120707Y-132333D01*
X121087Y-131917D01*
X121340Y-131417D01*
X121530Y-130750D01*
X121593Y-130000D01*
X121530Y-129250D01*
X121340Y-128583D01*
X121087Y-128083D01*
X120707Y-127667D01*
X120200Y-127500D01*
G01X123907Y-131500D02*
X124287Y-132083D01*
X124793Y-132417D01*
X125363Y-132500D01*
X125870Y-132417D01*
X126377Y-132000D01*
X126693Y-131500D01*
X126757Y-131000D01*
X126630Y-130417D01*
X126187Y-130000D01*
X125743Y-129833D01*
X125173D01*
G01X125743D02*
X126123Y-129583D01*
X126440Y-129167D01*
X126567Y-128667D01*
X126440Y-128167D01*
X126123Y-127750D01*
X125553Y-127500D01*
X124983Y-127583D01*
X124413Y-127917D01*
G01X130717Y-134167D02*
X131350Y-133333D01*
X131667Y-132500D01*
Y-129167D01*
X131350Y-128333D01*
X130717Y-127500D01*
G01X134107Y-131500D02*
X134487Y-132083D01*
X134993Y-132417D01*
X135563Y-132500D01*
X136070Y-132417D01*
X136577Y-132000D01*
X136893Y-131500D01*
X136957Y-131000D01*
X136830Y-130417D01*
X136387Y-130000D01*
X135943Y-129833D01*
X135373D01*
G01X135943D02*
X136323Y-129583D01*
X136640Y-129167D01*
X136767Y-128667D01*
X136640Y-128167D01*
X136323Y-127750D01*
X135753Y-127500D01*
X135183Y-127583D01*
X134613Y-127917D01*
G01X139523Y-131917D02*
X139967Y-132333D01*
X140473Y-132500D01*
X140980Y-132333D01*
X141423Y-131833D01*
X141740Y-131083D01*
X141867Y-130333D01*
Y-129417D01*
X141740Y-128667D01*
X141423Y-128000D01*
X141043Y-127667D01*
X140600Y-127500D01*
X140093Y-127667D01*
X139713Y-128000D01*
X139460Y-128500D01*
X139333Y-129167D01*
X139460Y-129750D01*
X139777Y-130333D01*
X140157Y-130667D01*
X140600Y-130750D01*
X141107Y-130583D01*
X141487Y-130167D01*
X141867Y-129417D01*
G01X145573Y-132500D02*
X145700Y-131417D01*
X145890Y-130500D01*
X146143Y-129667D01*
X146460Y-128750D01*
X146967Y-127500D01*
X144433D01*
G01X149977Y-130833D02*
X151623D01*
G01X154507Y-131500D02*
X154887Y-132083D01*
X155393Y-132417D01*
X155963Y-132500D01*
X156470Y-132417D01*
X156977Y-132000D01*
X157293Y-131500D01*
X157357Y-131000D01*
X157230Y-130417D01*
X156787Y-130000D01*
X156343Y-129833D01*
X155773D01*
G01X156343D02*
X156723Y-129583D01*
X157040Y-129167D01*
X157167Y-128667D01*
X157040Y-128167D01*
X156723Y-127750D01*
X156153Y-127500D01*
X155583Y-127583D01*
X155013Y-127917D01*
G01X159797Y-130417D02*
X160240Y-129833D01*
X160620Y-129500D01*
X161127Y-129333D01*
X161570Y-129500D01*
X161887Y-129833D01*
X162140Y-130333D01*
X162203Y-130917D01*
X162140Y-131417D01*
X161887Y-131917D01*
X161507Y-132333D01*
X161063Y-132500D01*
X160557Y-132333D01*
X160113Y-131833D01*
X159860Y-131083D01*
X159797Y-130250D01*
X159923Y-129167D01*
X160113Y-128583D01*
X160430Y-128000D01*
X160873Y-127583D01*
X161317Y-127500D01*
X161760Y-127667D01*
X162077Y-128083D01*
G01X166100Y-132500D02*
Y-127500D01*
X165340Y-128500D01*
G01Y-132500D02*
X166860D01*
G01X171960D02*
Y-127500D01*
X169617Y-131083D01*
X172783D01*
G01X191000Y-62500D02*
Y-137500D01*
G01Y-112500D02*
X294000D01*
Y-87500D01*
G01X191000D02*
X294000D01*
G01X301507Y-122500D02*
Y-117500D01*
X302773D01*
X303280Y-117750D01*
X303660Y-118083D01*
X303977Y-118583D01*
X304230Y-119167D01*
X304293Y-120000D01*
X304230Y-120833D01*
X303977Y-121417D01*
X303660Y-121917D01*
X303280Y-122250D01*
X302773Y-122500D01*
X301507D01*
G01X306417D02*
X308000Y-117500D01*
X309583Y-122500D01*
G01X309013Y-120750D02*
X306987D01*
G01X313100Y-117500D02*
Y-122500D01*
G01X311643Y-117500D02*
X314557D01*
G01X319467Y-122500D02*
X316933D01*
Y-117500D01*
X319467D01*
G01X318453Y-119917D02*
X316933D01*
G01X323300Y-122667D02*
X323173Y-122583D01*
Y-122417D01*
X323300Y-122333D01*
X323427Y-122417D01*
Y-122583D01*
X323300Y-122667D01*
G01Y-120417D02*
X323173Y-120333D01*
Y-120167D01*
X323300Y-120083D01*
X323427Y-120167D01*
Y-120333D01*
X323300Y-120417D01*
G01X296000Y-62500D02*
Y-137500D01*
G01X294000Y-62500D02*
Y-137500D01*
G01X301633Y-97500D02*
Y-92500D01*
X303153D01*
X303660Y-92750D01*
X304040Y-93333D01*
X304167Y-94000D01*
X304040Y-94667D01*
X303723Y-95167D01*
X303153Y-95417D01*
X301633D01*
G01X306860Y-97667D02*
X309140Y-92500D01*
G01X311643Y-97500D02*
Y-92500D01*
X314557Y-97500D01*
Y-92500D01*
G01X318200Y-97667D02*
X318073Y-97583D01*
Y-97417D01*
X318200Y-97333D01*
X318327Y-97417D01*
Y-97583D01*
X318200Y-97667D01*
G01Y-95417D02*
X318073Y-95333D01*
Y-95167D01*
X318200Y-95083D01*
X318327Y-95167D01*
Y-95333D01*
X318200Y-95417D01*
G01X296000Y-112500D02*
X496000D01*
G01X301633Y-72500D02*
Y-67500D01*
X303153D01*
X303660Y-67750D01*
X304040Y-68333D01*
X304167Y-69000D01*
X304040Y-69667D01*
X303723Y-70167D01*
X303153Y-70417D01*
X301633D01*
G01X306733Y-72500D02*
Y-67500D01*
X308317D01*
X308823Y-67750D01*
X309140Y-68083D01*
X309267Y-68750D01*
X309140Y-69417D01*
X308760Y-69833D01*
X308317Y-70083D01*
X306733D01*
G01X308317D02*
X309267Y-72500D01*
G01X313100D02*
X312593Y-72417D01*
X312150Y-72083D01*
X311770Y-71583D01*
X311517Y-71000D01*
X311390Y-70333D01*
Y-69667D01*
X311517Y-69000D01*
X311770Y-68417D01*
X312150Y-67917D01*
X312593Y-67583D01*
X313100Y-67500D01*
X313607Y-67583D01*
X314050Y-67917D01*
X314430Y-68417D01*
X314683Y-69000D01*
X314810Y-69667D01*
Y-70333D01*
X314683Y-71000D01*
X314430Y-71583D01*
X314050Y-72083D01*
X313607Y-72417D01*
X313100Y-72500D01*
G01X316933Y-71500D02*
X317250Y-72000D01*
X317630Y-72333D01*
X318073Y-72500D01*
X318580Y-72333D01*
X318960Y-72000D01*
X319340Y-71500D01*
X319467Y-70833D01*
Y-67500D01*
G01X324567Y-72500D02*
X322033D01*
Y-67500D01*
X324567D01*
G01X323553Y-69917D02*
X322033D01*
G01X329793Y-67917D02*
X329413Y-67667D01*
X328970Y-67500D01*
X328463D01*
X327893Y-67750D01*
X327450Y-68167D01*
X327133Y-68667D01*
X326880Y-69500D01*
X326817Y-70250D01*
X326943Y-71000D01*
X327133Y-71500D01*
X327513Y-72000D01*
X327957Y-72333D01*
X328400Y-72500D01*
X328843D01*
X329287Y-72333D01*
X329667Y-72083D01*
X329983Y-71750D01*
G01X333500Y-67500D02*
Y-72500D01*
G01X332043Y-67500D02*
X334957D01*
G01X338600Y-72667D02*
X338473Y-72583D01*
Y-72417D01*
X338600Y-72333D01*
X338727Y-72417D01*
Y-72583D01*
X338600Y-72667D01*
G01Y-70417D02*
X338473Y-70333D01*
Y-70167D01*
X338600Y-70083D01*
X338727Y-70167D01*
Y-70333D01*
X338600Y-70417D01*
G01X296000Y-87500D02*
X496000D01*
G01X411000Y-112500D02*
Y-137500D01*
G01X416633Y-122500D02*
Y-117500D01*
X418217D01*
X418723Y-117750D01*
X419040Y-118083D01*
X419167Y-118750D01*
X419040Y-119417D01*
X418660Y-119833D01*
X418217Y-120083D01*
X416633D01*
G01X418217D02*
X419167Y-122500D01*
G01X424267D02*
X421733D01*
Y-117500D01*
X424267D01*
G01X423253Y-119917D02*
X421733D01*
G01X426517Y-117500D02*
X428100Y-122500D01*
X429683Y-117500D01*
G01X433200Y-122667D02*
X433073Y-122583D01*
Y-122417D01*
X433200Y-122333D01*
X433327Y-122417D01*
Y-122583D01*
X433200Y-122667D01*
G01Y-120417D02*
X433073Y-120333D01*
Y-120167D01*
X433200Y-120083D01*
X433327Y-120167D01*
Y-120333D01*
X433200Y-120417D01*
G01X460000Y-112500D02*
Y-137500D01*
G01X-723776Y2987387D02*
Y-376795D01*
Y-489221D01*
X1782976D01*
Y-376795D01*
Y2987387D01*
X-723776D01*
G01X6705Y-124160D02*
X7332Y-124685D01*
X8037Y-125000D01*
X8663D01*
X9290Y-124685D01*
X9760Y-124160D01*
X9995Y-123425D01*
X9838Y-122690D01*
X9447Y-122060D01*
X8742Y-121640D01*
X7802Y-121430D01*
X7253Y-121010D01*
X7018Y-120275D01*
X7175Y-119540D01*
X7567Y-119015D01*
X8115Y-118700D01*
X8663D01*
X9212Y-118910D01*
X9682Y-119435D01*
G01X13005Y-125000D02*
Y-118700D01*
G01X16295D02*
Y-125000D01*
G01Y-121850D02*
X13005D01*
G01X20010Y-118700D02*
X21890D01*
G01X20950D02*
Y-125000D01*
G01X20010D02*
X21890D01*
G01X28817D02*
X25683D01*
Y-118700D01*
X28817D01*
G01X27563Y-121745D02*
X25683D01*
G01X31748Y-125000D02*
Y-118700D01*
X35352Y-125000D01*
Y-118700D01*
G01X39693Y-126155D02*
X40007Y-124790D01*
G01X46150Y-118700D02*
Y-125000D01*
G01X44348Y-118700D02*
X47952D01*
G01X50492Y-125000D02*
X52450Y-118700D01*
X54408Y-125000D01*
G01X53703Y-122795D02*
X51197D01*
G01X57810Y-118700D02*
X59690D01*
G01X58750D02*
Y-125000D01*
G01X57810D02*
X59690D01*
G01X62700Y-118700D02*
X63797Y-125000D01*
X65050Y-118700D01*
X66303Y-125000D01*
X67400Y-118700D01*
G01X69392Y-125000D02*
X71350Y-118700D01*
X73308Y-125000D01*
G01X72603Y-122795D02*
X70097D01*
G01X75848Y-125000D02*
Y-118700D01*
X79452Y-125000D01*
Y-118700D01*
G01X88683Y-125000D02*
Y-118700D01*
X90642D01*
X91268Y-119015D01*
X91660Y-119435D01*
X91817Y-120275D01*
X91660Y-121115D01*
X91190Y-121640D01*
X90642Y-121955D01*
X88683D01*
G01X90642D02*
X91817Y-125000D01*
G01X96550Y-125210D02*
X96393Y-125105D01*
Y-124895D01*
X96550Y-124790D01*
X96707Y-124895D01*
Y-125105D01*
X96550Y-125210D01*
G01X102850Y-125000D02*
X102223Y-124895D01*
X101675Y-124475D01*
X101205Y-123845D01*
X100892Y-123110D01*
X100735Y-122270D01*
Y-121430D01*
X100892Y-120590D01*
X101205Y-119855D01*
X101675Y-119225D01*
X102223Y-118805D01*
X102850Y-118700D01*
X103477Y-118805D01*
X104025Y-119225D01*
X104495Y-119855D01*
X104808Y-120590D01*
X104965Y-121430D01*
Y-122270D01*
X104808Y-123110D01*
X104495Y-123845D01*
X104025Y-124475D01*
X103477Y-124895D01*
X102850Y-125000D01*
G01X109150Y-125210D02*
X108993Y-125105D01*
Y-124895D01*
X109150Y-124790D01*
X109307Y-124895D01*
Y-125105D01*
X109150Y-125210D01*
G01X117173Y-119225D02*
X116703Y-118910D01*
X116155Y-118700D01*
X115528D01*
X114823Y-119015D01*
X114275Y-119540D01*
X113883Y-120170D01*
X113570Y-121220D01*
X113492Y-122165D01*
X113648Y-123110D01*
X113883Y-123740D01*
X114353Y-124370D01*
X114902Y-124790D01*
X115450Y-125000D01*
X115998D01*
X116547Y-124790D01*
X117017Y-124475D01*
X117408Y-124055D01*
G01X121750Y-125210D02*
X121593Y-125105D01*
Y-124895D01*
X121750Y-124790D01*
X121907Y-124895D01*
Y-125105D01*
X121750Y-125210D01*
G01X6627Y-115000D02*
Y-108700D01*
G01X9603D02*
X6627Y-112585D01*
G01X10073Y-115000D02*
X7958Y-110800D01*
G01X12927Y-108700D02*
Y-113215D01*
X13240Y-114160D01*
X13867Y-114790D01*
X14650Y-115000D01*
X15433Y-114790D01*
X16060Y-114160D01*
X16373Y-113215D01*
Y-108700D01*
G01X22517Y-115000D02*
X19383D01*
Y-108700D01*
X22517D01*
G01X21263Y-111745D02*
X19383D01*
G01X26310Y-108700D02*
X28190D01*
G01X27250D02*
Y-115000D01*
G01X26310D02*
X28190D01*
G01X38205Y-114160D02*
X38832Y-114685D01*
X39537Y-115000D01*
X40163D01*
X40790Y-114685D01*
X41260Y-114160D01*
X41495Y-113425D01*
X41338Y-112690D01*
X40947Y-112060D01*
X40242Y-111640D01*
X39302Y-111430D01*
X38753Y-111010D01*
X38518Y-110275D01*
X38675Y-109540D01*
X39067Y-109015D01*
X39615Y-108700D01*
X40163D01*
X40712Y-108910D01*
X41182Y-109435D01*
G01X44505Y-115000D02*
Y-108700D01*
G01X47795D02*
Y-115000D01*
G01Y-111850D02*
X44505D01*
G01X50492Y-115000D02*
X52450Y-108700D01*
X54408Y-115000D01*
G01X53703Y-112795D02*
X51197D01*
G01X56948Y-115000D02*
Y-108700D01*
X60552Y-115000D01*
Y-108700D01*
G01X69705Y-115000D02*
Y-108700D01*
G01X72995D02*
Y-115000D01*
G01Y-111850D02*
X69705D01*
G01X76005Y-114160D02*
X76632Y-114685D01*
X77337Y-115000D01*
X77963D01*
X78590Y-114685D01*
X79060Y-114160D01*
X79295Y-113425D01*
X79138Y-112690D01*
X78747Y-112060D01*
X78042Y-111640D01*
X77102Y-111430D01*
X76553Y-111010D01*
X76318Y-110275D01*
X76475Y-109540D01*
X76867Y-109015D01*
X77415Y-108700D01*
X77963D01*
X78512Y-108910D01*
X78982Y-109435D01*
G01X83010Y-108700D02*
X84890D01*
G01X83950D02*
Y-115000D01*
G01X83010D02*
X84890D01*
G01X88292D02*
X90250Y-108700D01*
X92208Y-115000D01*
G01X91503Y-112795D02*
X88997D01*
G01X94748Y-115000D02*
Y-108700D01*
X98352Y-115000D01*
Y-108700D01*
G01X103320Y-111850D02*
X104887D01*
Y-113740D01*
X104417Y-114370D01*
X103868Y-114790D01*
X103085Y-115000D01*
X102302Y-114790D01*
X101753Y-114370D01*
X101283Y-113740D01*
X100970Y-113005D01*
X100813Y-112165D01*
Y-111430D01*
X100970Y-110800D01*
X101283Y-110065D01*
X101753Y-109435D01*
X102223Y-109015D01*
X102850Y-108700D01*
X103398D01*
X104025Y-108910D01*
X104495Y-109330D01*
G01X108993Y-116155D02*
X109307Y-114790D01*
G01X115450Y-108700D02*
Y-115000D01*
G01X113648Y-108700D02*
X117252D01*
G01X119792Y-115000D02*
X121750Y-108700D01*
X123708Y-115000D01*
G01X123003Y-112795D02*
X120497D01*
G01X128050Y-115000D02*
X127423Y-114895D01*
X126875Y-114475D01*
X126405Y-113845D01*
X126092Y-113110D01*
X125935Y-112270D01*
Y-111430D01*
X126092Y-110590D01*
X126405Y-109855D01*
X126875Y-109225D01*
X127423Y-108805D01*
X128050Y-108700D01*
X128677Y-108805D01*
X129225Y-109225D01*
X129695Y-109855D01*
X130008Y-110590D01*
X130165Y-111430D01*
Y-112270D01*
X130008Y-113110D01*
X129695Y-113845D01*
X129225Y-114475D01*
X128677Y-114895D01*
X128050Y-115000D01*
G01X140650D02*
Y-112165D01*
X139083Y-108700D01*
G01X142217D02*
X140650Y-112165D01*
G01X145227Y-108700D02*
Y-113215D01*
X145540Y-114160D01*
X146167Y-114790D01*
X146950Y-115000D01*
X147733Y-114790D01*
X148360Y-114160D01*
X148673Y-113215D01*
Y-108700D01*
G01X151292Y-115000D02*
X153250Y-108700D01*
X155208Y-115000D01*
G01X154503Y-112795D02*
X151997D01*
G01X157748Y-115000D02*
Y-108700D01*
X161352Y-115000D01*
Y-108700D01*
G01X30650Y-92300D02*
X28130Y-91883D01*
X25925Y-90217D01*
X24035Y-87717D01*
X22775Y-84800D01*
X22145Y-81467D01*
Y-78133D01*
X22775Y-74800D01*
X24035Y-71883D01*
X25925Y-69384D01*
X28130Y-67717D01*
X30650Y-67300D01*
X33170Y-67717D01*
X35375Y-69384D01*
X37265Y-71883D01*
X38525Y-74800D01*
X39155Y-78133D01*
Y-81467D01*
X38525Y-84800D01*
X37265Y-87717D01*
X35375Y-90217D01*
X33170Y-91883D01*
X30650Y-92300D01*
G01X33170Y-85633D02*
X36950Y-92300D01*
G01X50495Y-75634D02*
Y-87300D01*
X51755Y-90217D01*
X53645Y-91883D01*
X55850Y-92300D01*
X58055Y-91883D01*
X59945Y-90217D01*
X61205Y-87300D01*
G01Y-92300D02*
Y-75634D01*
G01X86720Y-92300D02*
Y-75634D01*
G01Y-78550D02*
X85460Y-76884D01*
X83570Y-76050D01*
X81365Y-75634D01*
X79160Y-76467D01*
X77270Y-78133D01*
X76010Y-80634D01*
X75380Y-83967D01*
X76010Y-87300D01*
X77270Y-89801D01*
X79160Y-91467D01*
X81365Y-92300D01*
X83570Y-91883D01*
X85460Y-90634D01*
X86720Y-88967D01*
G01X100895Y-92300D02*
Y-75634D01*
G01Y-79800D02*
X102155Y-77717D01*
X104045Y-76050D01*
X106565Y-75634D01*
X108770Y-76050D01*
X110660Y-77717D01*
X111605Y-80634D01*
Y-92300D01*
G01X131450Y-67300D02*
Y-92300D01*
G01X127040Y-75634D02*
X135860D01*
G01X162320Y-92300D02*
Y-75634D01*
G01Y-78550D02*
X161060Y-76884D01*
X159170Y-76050D01*
X156965Y-75634D01*
X154760Y-76467D01*
X152870Y-78133D01*
X151610Y-80634D01*
X150980Y-83967D01*
X151610Y-87300D01*
X152870Y-89801D01*
X154760Y-91467D01*
X156965Y-92300D01*
X159170Y-91883D01*
X161060Y-90634D01*
X162320Y-88967D01*
G01X6548Y-105000D02*
Y-98700D01*
X10152Y-105000D01*
Y-98700D01*
G01X14650Y-105000D02*
X14023Y-104895D01*
X13475Y-104475D01*
X13005Y-103845D01*
X12692Y-103110D01*
X12535Y-102270D01*
Y-101430D01*
X12692Y-100590D01*
X13005Y-99855D01*
X13475Y-99225D01*
X14023Y-98805D01*
X14650Y-98700D01*
X15277Y-98805D01*
X15825Y-99225D01*
X16295Y-99855D01*
X16608Y-100590D01*
X16765Y-101430D01*
Y-102270D01*
X16608Y-103110D01*
X16295Y-103845D01*
X15825Y-104475D01*
X15277Y-104895D01*
X14650Y-105000D01*
G01X20950Y-105210D02*
X20793Y-105105D01*
Y-104895D01*
X20950Y-104790D01*
X21107Y-104895D01*
Y-105105D01*
X20950Y-105210D01*
G01X27250Y-105000D02*
Y-98700D01*
X26310Y-99960D01*
G01Y-105000D02*
X28190D01*
G01X33550D02*
X34098Y-104895D01*
X34725Y-104580D01*
X35117Y-104055D01*
X35273Y-103320D01*
X35117Y-102585D01*
X34647Y-101955D01*
X33942Y-101640D01*
X33158D01*
X32688Y-101430D01*
X32297Y-100905D01*
X32140Y-100170D01*
X32375Y-99435D01*
X32923Y-98910D01*
X33550Y-98700D01*
X34177Y-98910D01*
X34725Y-99435D01*
X34960Y-100170D01*
X34803Y-100905D01*
X34412Y-101430D01*
X33942Y-101640D01*
X33158D01*
X32453Y-101955D01*
X31983Y-102585D01*
X31827Y-103320D01*
X31983Y-104055D01*
X32375Y-104580D01*
X33002Y-104895D01*
X33550Y-105000D01*
G01X39850D02*
X40398Y-104895D01*
X41025Y-104580D01*
X41417Y-104055D01*
X41573Y-103320D01*
X41417Y-102585D01*
X40947Y-101955D01*
X40242Y-101640D01*
X39458D01*
X38988Y-101430D01*
X38597Y-100905D01*
X38440Y-100170D01*
X38675Y-99435D01*
X39223Y-98910D01*
X39850Y-98700D01*
X40477Y-98910D01*
X41025Y-99435D01*
X41260Y-100170D01*
X41103Y-100905D01*
X40712Y-101430D01*
X40242Y-101640D01*
X39458D01*
X38753Y-101955D01*
X38283Y-102585D01*
X38127Y-103320D01*
X38283Y-104055D01*
X38675Y-104580D01*
X39302Y-104895D01*
X39850Y-105000D01*
G01X45993Y-106155D02*
X46307Y-104790D01*
G01X50100Y-98700D02*
X51197Y-105000D01*
X52450Y-98700D01*
X53703Y-105000D01*
X54800Y-98700D01*
G01X60317Y-105000D02*
X57183D01*
Y-98700D01*
X60317D01*
G01X59063Y-101745D02*
X57183D01*
G01X63248Y-105000D02*
Y-98700D01*
X66852Y-105000D01*
Y-98700D01*
G01X76005Y-105000D02*
Y-98700D01*
G01X79295D02*
Y-105000D01*
G01Y-101850D02*
X76005D01*
G01X81600Y-98700D02*
X82697Y-105000D01*
X83950Y-98700D01*
X85203Y-105000D01*
X86300Y-98700D01*
G01X88292Y-105000D02*
X90250Y-98700D01*
X92208Y-105000D01*
G01X91503Y-102795D02*
X88997D01*
G01X101362Y-99750D02*
X101832Y-99120D01*
X102380Y-98805D01*
X103007Y-98700D01*
X103790Y-98910D01*
X104338Y-99435D01*
X104495Y-100065D01*
X104417Y-100695D01*
X104103Y-101220D01*
X102537Y-102270D01*
X101832Y-103005D01*
X101362Y-104055D01*
X101205Y-105000D01*
X104495D01*
G01X107348D02*
Y-98700D01*
X110952Y-105000D01*
Y-98700D01*
G01X113727Y-105000D02*
Y-98700D01*
X115293D01*
X115920Y-99015D01*
X116390Y-99435D01*
X116782Y-100065D01*
X117095Y-100800D01*
X117173Y-101850D01*
X117095Y-102900D01*
X116782Y-103635D01*
X116390Y-104265D01*
X115920Y-104685D01*
X115293Y-105000D01*
X113727D01*
G01X126483D02*
Y-98700D01*
X128442D01*
X129068Y-99015D01*
X129460Y-99435D01*
X129617Y-100275D01*
X129460Y-101115D01*
X128990Y-101640D01*
X128442Y-101955D01*
X126483D01*
G01X128442D02*
X129617Y-105000D01*
G01X132627D02*
Y-98700D01*
X134193D01*
X134820Y-99015D01*
X135290Y-99435D01*
X135682Y-100065D01*
X135995Y-100800D01*
X136073Y-101850D01*
X135995Y-102900D01*
X135682Y-103635D01*
X135290Y-104265D01*
X134820Y-104685D01*
X134193Y-105000D01*
X132627D01*
G01X140650Y-105210D02*
X140493Y-105105D01*
Y-104895D01*
X140650Y-104790D01*
X140807Y-104895D01*
Y-105105D01*
X140650Y-105210D01*
G01X202000Y-72000D02*
Y-80000D01*
X206000D01*
G01X213800D02*
Y-74667D01*
G01Y-75600D02*
X213400Y-75067D01*
X212800Y-74800D01*
X212100Y-74667D01*
X211400Y-74933D01*
X210800Y-75467D01*
X210400Y-76267D01*
X210200Y-77333D01*
X210400Y-78400D01*
X210800Y-79200D01*
X211400Y-79733D01*
X212100Y-80000D01*
X212800Y-79867D01*
X213400Y-79467D01*
X213800Y-78934D01*
G01X217900Y-82400D02*
X218500Y-82667D01*
X219300Y-82400D01*
X219800Y-81867D01*
X220200Y-81200D01*
X220800Y-79067D01*
X222100Y-74667D01*
G01X218900D02*
X220800Y-79067D01*
G01X226500Y-76400D02*
X229700D01*
X229400Y-75467D01*
X228900Y-74933D01*
X228200Y-74667D01*
X227500Y-74800D01*
X226900Y-75200D01*
X226500Y-76133D01*
X226300Y-76934D01*
Y-77733D01*
X226500Y-78533D01*
X227000Y-79333D01*
X227600Y-79867D01*
X228300Y-80000D01*
X229000Y-79733D01*
X229700Y-78934D01*
G01X234600Y-80000D02*
Y-74667D01*
G01Y-75733D02*
X235100Y-75200D01*
X235600Y-74800D01*
X236300Y-74667D01*
X236800Y-74800D01*
X237400Y-75200D01*
G01X225500Y-122000D02*
Y-130000D01*
G01X223200Y-122000D02*
X227800D01*
G01X233500Y-124667D02*
Y-130000D01*
G01Y-122533D02*
X233300Y-122400D01*
Y-122133D01*
X233500Y-122000D01*
X233700Y-122133D01*
Y-122400D01*
X233500Y-122533D01*
G01X239800Y-130000D02*
Y-124667D01*
G01Y-126000D02*
X240200Y-125333D01*
X240800Y-124800D01*
X241600Y-124667D01*
X242300Y-124800D01*
X242900Y-125333D01*
X243200Y-126267D01*
Y-130000D01*
G01X251300D02*
Y-124667D01*
G01Y-125600D02*
X250900Y-125067D01*
X250300Y-124800D01*
X249600Y-124667D01*
X248900Y-124933D01*
X248300Y-125467D01*
X247900Y-126267D01*
X247700Y-127333D01*
X247900Y-128400D01*
X248300Y-129200D01*
X248900Y-129733D01*
X249600Y-130000D01*
X250300Y-129867D01*
X250900Y-129467D01*
X251300Y-128934D01*
G01X231100Y-101000D02*
X233100D01*
Y-103400D01*
X232500Y-104200D01*
X231800Y-104733D01*
X230800Y-105000D01*
X229800Y-104733D01*
X229100Y-104200D01*
X228500Y-103400D01*
X228100Y-102467D01*
X227900Y-101400D01*
Y-100467D01*
X228100Y-99667D01*
X228500Y-98733D01*
X229100Y-97933D01*
X229700Y-97400D01*
X230500Y-97000D01*
X231200D01*
X232000Y-97267D01*
X232600Y-97800D01*
G01X236200Y-105000D02*
Y-97000D01*
X240800Y-105000D01*
Y-97000D01*
G01X244300Y-105000D02*
Y-97000D01*
X246300D01*
X247100Y-97400D01*
X247700Y-97933D01*
X248200Y-98733D01*
X248600Y-99667D01*
X248700Y-101000D01*
X248600Y-102333D01*
X248200Y-103267D01*
X247700Y-104067D01*
X247100Y-104600D01*
X246300Y-105000D01*
X244300D01*
G01X253600Y-73333D02*
X254200Y-72533D01*
X254900Y-72133D01*
X255700Y-72000D01*
X256700Y-72267D01*
X257400Y-72933D01*
X257600Y-73733D01*
X257500Y-74534D01*
X257100Y-75200D01*
X255100Y-76533D01*
X254200Y-77467D01*
X253600Y-78800D01*
X253400Y-80000D01*
X257600D01*
G01X328600Y-123333D02*
X329200Y-122533D01*
X329900Y-122133D01*
X330700Y-122000D01*
X331700Y-122267D01*
X332400Y-122933D01*
X332600Y-123733D01*
X332500Y-124534D01*
X332100Y-125200D01*
X330100Y-126533D01*
X329200Y-127467D01*
X328600Y-128800D01*
X328400Y-130000D01*
X332600D01*
G01X338500Y-122000D02*
X337700Y-122267D01*
X337100Y-122933D01*
X336700Y-123733D01*
X336400Y-124800D01*
X336300Y-126000D01*
X336400Y-127200D01*
X336700Y-128267D01*
X337100Y-129067D01*
X337700Y-129733D01*
X338500Y-130000D01*
X339300Y-129733D01*
X339900Y-129067D01*
X340300Y-128267D01*
X340600Y-127200D01*
X340700Y-126000D01*
X340600Y-124800D01*
X340300Y-123733D01*
X339900Y-122933D01*
X339300Y-122267D01*
X338500Y-122000D01*
G01X346500Y-130000D02*
Y-122000D01*
X345300Y-123600D01*
G01Y-130000D02*
X347700D01*
G01X352300Y-128400D02*
X352900Y-129333D01*
X353700Y-129867D01*
X354600Y-130000D01*
X355400Y-129867D01*
X356200Y-129200D01*
X356700Y-128400D01*
X356800Y-127600D01*
X356600Y-126667D01*
X355900Y-126000D01*
X355200Y-125733D01*
X354300D01*
G01X355200D02*
X355800Y-125333D01*
X356300Y-124667D01*
X356500Y-123867D01*
X356300Y-123067D01*
X355800Y-122400D01*
X354900Y-122000D01*
X354000Y-122133D01*
X353100Y-122667D01*
G01X360700Y-130267D02*
X364300Y-122000D01*
G01X370500D02*
X369700Y-122267D01*
X369100Y-122933D01*
X368700Y-123733D01*
X368400Y-124800D01*
X368300Y-126000D01*
X368400Y-127200D01*
X368700Y-128267D01*
X369100Y-129067D01*
X369700Y-129733D01*
X370500Y-130000D01*
X371300Y-129733D01*
X371900Y-129067D01*
X372300Y-128267D01*
X372600Y-127200D01*
X372700Y-126000D01*
X372600Y-124800D01*
X372300Y-123733D01*
X371900Y-122933D01*
X371300Y-122267D01*
X370500Y-122000D01*
G01X378500Y-130000D02*
Y-122000D01*
X377300Y-123600D01*
G01Y-130000D02*
X379700D01*
G01X384700Y-130267D02*
X388300Y-122000D01*
G01X394500D02*
X393700Y-122267D01*
X393100Y-122933D01*
X392700Y-123733D01*
X392400Y-124800D01*
X392300Y-126000D01*
X392400Y-127200D01*
X392700Y-128267D01*
X393100Y-129067D01*
X393700Y-129733D01*
X394500Y-130000D01*
X395300Y-129733D01*
X395900Y-129067D01*
X396300Y-128267D01*
X396600Y-127200D01*
X396700Y-126000D01*
X396600Y-124800D01*
X396300Y-123733D01*
X395900Y-122933D01*
X395300Y-122267D01*
X394500Y-122000D01*
G01X400800Y-129067D02*
X401500Y-129733D01*
X402300Y-130000D01*
X403100Y-129733D01*
X403800Y-128934D01*
X404300Y-127733D01*
X404500Y-126533D01*
Y-125067D01*
X404300Y-123867D01*
X403800Y-122800D01*
X403200Y-122267D01*
X402500Y-122000D01*
X401700Y-122267D01*
X401100Y-122800D01*
X400700Y-123600D01*
X400500Y-124667D01*
X400700Y-125600D01*
X401200Y-126533D01*
X401800Y-127067D01*
X402500Y-127200D01*
X403300Y-126934D01*
X403900Y-126267D01*
X404500Y-125067D01*
G01X328300Y-105000D02*
Y-97000D01*
X330300D01*
X331100Y-97400D01*
X331700Y-97933D01*
X332200Y-98733D01*
X332600Y-99667D01*
X332700Y-101000D01*
X332600Y-102333D01*
X332200Y-103267D01*
X331700Y-104067D01*
X331100Y-104600D01*
X330300Y-105000D01*
X328300D01*
G01X336000D02*
X338500Y-97000D01*
X341000Y-105000D01*
G01X340100Y-102200D02*
X336900D01*
G01X346500Y-97000D02*
Y-105000D01*
G01X344200Y-97000D02*
X348800D01*
G01X352600Y-101667D02*
X353300Y-100733D01*
X353900Y-100200D01*
X354700Y-99933D01*
X355400Y-100200D01*
X355900Y-100733D01*
X356300Y-101533D01*
X356400Y-102467D01*
X356300Y-103267D01*
X355900Y-104067D01*
X355300Y-104733D01*
X354600Y-105000D01*
X353800Y-104733D01*
X353100Y-103934D01*
X352700Y-102733D01*
X352600Y-101400D01*
X352800Y-99667D01*
X353100Y-98733D01*
X353600Y-97800D01*
X354300Y-97133D01*
X355000Y-97000D01*
X355700Y-97267D01*
X356200Y-97933D01*
G01X359900Y-105000D02*
Y-97000D01*
X362500Y-103667D01*
X365100Y-97000D01*
Y-105000D01*
G01X370500Y-97000D02*
Y-105000D01*
G01X368200Y-97000D02*
X372800D01*
G01X379300Y-100733D02*
X379700Y-100333D01*
X380000Y-99667D01*
X380200Y-98733D01*
X380000Y-97933D01*
X379600Y-97400D01*
X378900Y-97000D01*
X376200D01*
Y-105000D01*
X379500D01*
X380200Y-104467D01*
X380600Y-103667D01*
X380800Y-102733D01*
X380600Y-101800D01*
X380000Y-101000D01*
X379300Y-100733D01*
X376200D01*
G01X386500Y-105000D02*
X387200Y-104867D01*
X388000Y-104467D01*
X388500Y-103800D01*
X388700Y-102867D01*
X388500Y-101934D01*
X387900Y-101133D01*
X387000Y-100733D01*
X386000D01*
X385400Y-100467D01*
X384900Y-99800D01*
X384700Y-98867D01*
X385000Y-97933D01*
X385700Y-97267D01*
X386500Y-97000D01*
X387300Y-97267D01*
X388000Y-97933D01*
X388300Y-98867D01*
X388100Y-99800D01*
X387600Y-100467D01*
X387000Y-100733D01*
X386000D01*
X385100Y-101133D01*
X384500Y-101934D01*
X384300Y-102867D01*
X384500Y-103800D01*
X385000Y-104467D01*
X385800Y-104867D01*
X386500Y-105000D01*
G01X394500D02*
X395200Y-104867D01*
X396000Y-104467D01*
X396500Y-103800D01*
X396700Y-102867D01*
X396500Y-101934D01*
X395900Y-101133D01*
X395000Y-100733D01*
X394000D01*
X393400Y-100467D01*
X392900Y-99800D01*
X392700Y-98867D01*
X393000Y-97933D01*
X393700Y-97267D01*
X394500Y-97000D01*
X395300Y-97267D01*
X396000Y-97933D01*
X396300Y-98867D01*
X396100Y-99800D01*
X395600Y-100467D01*
X395000Y-100733D01*
X394000D01*
X393100Y-101133D01*
X392500Y-101934D01*
X392300Y-102867D01*
X392500Y-103800D01*
X393000Y-104467D01*
X393800Y-104867D01*
X394500Y-105000D01*
G01X400000D02*
X402500Y-97000D01*
X405000Y-105000D01*
G01X404100Y-102200D02*
X400900D01*
G01X410500Y-97000D02*
X409700Y-97267D01*
X409100Y-97933D01*
X408700Y-98733D01*
X408400Y-99800D01*
X408300Y-101000D01*
X408400Y-102200D01*
X408700Y-103267D01*
X409100Y-104067D01*
X409700Y-104733D01*
X410500Y-105000D01*
X411300Y-104733D01*
X411900Y-104067D01*
X412300Y-103267D01*
X412600Y-102200D01*
X412700Y-101000D01*
X412600Y-99800D01*
X412300Y-98733D01*
X411900Y-97933D01*
X411300Y-97267D01*
X410500Y-97000D01*
G01X350500Y-72000D02*
Y-80000D01*
G01X348200Y-72000D02*
X352800D01*
G01X356600Y-76667D02*
X357300Y-75733D01*
X357900Y-75200D01*
X358700Y-74933D01*
X359400Y-75200D01*
X359900Y-75733D01*
X360300Y-76533D01*
X360400Y-77467D01*
X360300Y-78267D01*
X359900Y-79067D01*
X359300Y-79733D01*
X358600Y-80000D01*
X357800Y-79733D01*
X357100Y-78934D01*
X356700Y-77733D01*
X356600Y-76400D01*
X356800Y-74667D01*
X357100Y-73733D01*
X357600Y-72800D01*
X358300Y-72133D01*
X359000Y-72000D01*
X359700Y-72267D01*
X360200Y-72933D01*
G01X363900Y-80000D02*
Y-72000D01*
X366500Y-78667D01*
X369100Y-72000D01*
Y-80000D01*
G01X375100Y-76000D02*
X377100D01*
Y-78400D01*
X376500Y-79200D01*
X375800Y-79733D01*
X374800Y-80000D01*
X373800Y-79733D01*
X373100Y-79200D01*
X372500Y-78400D01*
X372100Y-77467D01*
X371900Y-76400D01*
Y-75467D01*
X372100Y-74667D01*
X372500Y-73733D01*
X373100Y-72933D01*
X373700Y-72400D01*
X374500Y-72000D01*
X375200D01*
X376000Y-72267D01*
X376600Y-72800D01*
G01X379500Y-82667D02*
X385500D01*
G01X388500Y-80000D02*
Y-72000D01*
X390900D01*
X391700Y-72400D01*
X392300Y-73333D01*
X392500Y-74400D01*
X392300Y-75467D01*
X391800Y-76267D01*
X390900Y-76667D01*
X388500D01*
G01X396300Y-80000D02*
Y-72000D01*
X398300D01*
X399100Y-72400D01*
X399700Y-72933D01*
X400200Y-73733D01*
X400600Y-74667D01*
X400700Y-76000D01*
X400600Y-77333D01*
X400200Y-78267D01*
X399700Y-79067D01*
X399100Y-79600D01*
X398300Y-80000D01*
X396300D01*
G01X407300Y-75733D02*
X407700Y-75333D01*
X408000Y-74667D01*
X408200Y-73733D01*
X408000Y-72933D01*
X407600Y-72400D01*
X406900Y-72000D01*
X404200D01*
Y-80000D01*
X407500D01*
X408200Y-79467D01*
X408600Y-78667D01*
X408800Y-77733D01*
X408600Y-76800D01*
X408000Y-76000D01*
X407300Y-75733D01*
X404200D01*
G01X411500Y-82667D02*
X417500D01*
G01X420000Y-80000D02*
X422500Y-72000D01*
X425000Y-80000D01*
G01X424100Y-77200D02*
X420900D01*
G01X427500Y-82667D02*
X433500D01*
G01X439300Y-75733D02*
X439700Y-75333D01*
X440000Y-74667D01*
X440200Y-73733D01*
X440000Y-72933D01*
X439600Y-72400D01*
X438900Y-72000D01*
X436200D01*
Y-80000D01*
X439500D01*
X440200Y-79467D01*
X440600Y-78667D01*
X440800Y-77733D01*
X440600Y-76800D01*
X440000Y-76000D01*
X439300Y-75733D01*
X436200D01*
G01X444300Y-80000D02*
Y-72000D01*
X446300D01*
X447100Y-72400D01*
X447700Y-72933D01*
X448200Y-73733D01*
X448600Y-74667D01*
X448700Y-76000D01*
X448600Y-77333D01*
X448200Y-78267D01*
X447700Y-79067D01*
X447100Y-79600D01*
X446300Y-80000D01*
X444300D01*
G01X443000Y-130000D02*
X445500Y-122000D01*
X448000Y-130000D01*
G01X447100Y-127200D02*
X443900D01*
G01X473000Y-130000D02*
Y-122000D01*
X471800Y-123600D01*
G01Y-130000D02*
X474200D01*
G01X479100Y-126667D02*
X479800Y-125733D01*
X480400Y-125200D01*
X481200Y-124933D01*
X481900Y-125200D01*
X482400Y-125733D01*
X482800Y-126533D01*
X482900Y-127467D01*
X482800Y-128267D01*
X482400Y-129067D01*
X481800Y-129733D01*
X481100Y-130000D01*
X480300Y-129733D01*
X479600Y-128934D01*
X479200Y-127733D01*
X479100Y-126400D01*
X479300Y-124667D01*
X479600Y-123733D01*
X480100Y-122800D01*
X480800Y-122133D01*
X481500Y-122000D01*
X482200Y-122267D01*
X482700Y-122933D01*
M02*
